(lib_symbols
	(symbol "antmicroCapacitors0402:C_100n_0402"
			(pin_numbers
				(hide yes)
			)
			(pin_names
				(hide yes)
			)
			(exclude_from_sim no)
			(in_bom yes)
			(on_board yes)
			(property "Reference" "C"
				(at 20.32 -5.08 0)
				(effects
					(font
						(size 1.27 1.27)
						(thickness 0.15)
					)
					(justify left bottom)
				)
			)
			(property "Value" "C_100n_0402"
				(at 20.32 -10.16 0)
				(effects
					(font
						(size 1.27 1.27)
						(thickness 0.15)
					)
					(justify left bottom)
					(hide yes)
				)
			)
			(property "Footprint" "antmicro-footprints:C_0402_1005Metric"
				(at 20.32 -12.7 0)
				(effects
					(font
						(size 1.27 1.27)
						(thickness 0.15)
					)
					(justify left bottom)
					(hide yes)
				)
			)
			(property "Datasheet" "https://search.murata.co.jp/Ceramy/image/img/A01X/G101/ENG/GRM155R61H104KE14-01.pdf"
				(at 20.32 -15.24 0)
				(effects
					(font
						(size 1.27 1.27)
						(thickness 0.15)
					)
					(justify left bottom)
					(hide yes)
				)
			)
			(property "Description" ""
				(at 0 0 0)
				(effects
					(font
						(size 1.27 1.27)
					)
					(hide yes)
				)
			)
			(property "MPN" "GRM155R61H104KE14D"
				(at 20.32 -17.78 0)
				(effects
					(font
						(size 1.27 1.27)
						(thickness 0.15)
					)
					(justify left bottom)
					(hide yes)
				)
			)
			(property "Manufacturer" "Murata"
				(at 20.32 -20.32 0)
				(effects
					(font
						(size 1.27 1.27)
						(thickness 0.15)
					)
					(justify left bottom)
					(hide yes)
				)
			)
			(property "License" "Apache-2.0"
				(at 20.32 -22.86 0)
				(effects
					(font
						(size 1.27 1.27)
						(thickness 0.15)
					)
					(justify left bottom)
					(hide yes)
				)
			)
			(property "Author" "Antmicro"
				(at 20.32 -25.4 0)
				(effects
					(font
						(size 1.27 1.27)
						(thickness 0.15)
					)
					(justify left bottom)
					(hide yes)
				)
			)
			(property "Val" "100n"
				(at 20.32 -7.62 0)
				(effects
					(font
						(size 1.27 1.27)
						(thickness 0.15)
					)
					(justify left bottom)
				)
			)
			(property "Voltage" "50V"
				(at 20.32 -27.94 0)
				(effects
					(font
						(size 1.27 1.27)
					)
					(justify left bottom)
					(hide yes)
				)
			)
			(property "Dielectric" "X5R"
				(at 20.32 -30.48 0)
				(effects
					(font
						(size 1.27 1.27)
					)
					(justify left bottom)
					(hide yes)
				)
			)
			(symbol "C_100n_0402_0_1"
				(polyline
					(pts
						(xy 2.032 -1.524) (xy 2.032 1.524)
					)
					(stroke
						(width 0.3048)
						(type default)
					)
					(fill
						(type none)
					)
				)
				(polyline
					(pts
						(xy 3.048 -1.524) (xy 3.048 1.524)
					)
					(stroke
						(width 0.3302)
						(type default)
					)
					(fill
						(type none)
					)
				)
			)
			(symbol "C_100n_0402_1_1"
				(pin passive line
					(at 0 0 0)
					(length 2.032)
					(name "~"
						(effects
							(font
								(size 1.27 1.27)
							)
						)
					)
					(number "1"
						(effects
							(font
								(size 1.27 1.27)
							)
						)
					)
				)
				(pin passive line
					(at 5.08 0 180)
					(length 2.032)
					(name "~"
						(effects
							(font
								(size 1.27 1.27)
							)
						)
					)
					(number "2"
						(effects
							(font
								(size 1.27 1.27)
							)
						)
					)
				)
			)
		)
	(symbol "antmicroCapacitors0402:C_4u7_0402"
			(pin_numbers
				(hide yes)
			)
			(pin_names
				(hide yes)
			)
			(exclude_from_sim no)
			(in_bom yes)
			(on_board yes)
			(property "Reference" "C"
				(at 20.32 -5.08 0)
				(effects
					(font
						(size 1.27 1.27)
						(thickness 0.15)
					)
					(justify left bottom)
				)
			)
			(property "Value" "C_4u7_0402"
				(at 20.32 -10.16 0)
				(effects
					(font
						(size 1.27 1.27)
						(thickness 0.15)
					)
					(justify left bottom)
					(hide yes)
				)
			)
			(property "Footprint" "antmicro-footprints:C_0402_1005Metric"
				(at 20.32 -12.7 0)
				(effects
					(font
						(size 1.27 1.27)
						(thickness 0.15)
					)
					(justify left bottom)
					(hide yes)
				)
			)
			(property "Datasheet" ""
				(at 20.32 -15.24 0)
				(effects
					(font
						(size 1.27 1.27)
						(thickness 0.15)
					)
					(justify left bottom)
					(hide yes)
				)
			)
			(property "Description" ""
				(at 0 0 0)
				(effects
					(font
						(size 1.27 1.27)
					)
					(hide yes)
				)
			)
			(property "MPN" "GRM155R61A475MEAAD"
				(at 20.32 -17.78 0)
				(effects
					(font
						(size 1.27 1.27)
						(thickness 0.15)
					)
					(justify left bottom)
					(hide yes)
				)
			)
			(property "Manufacturer" "Murata"
				(at 20.32 -20.32 0)
				(effects
					(font
						(size 1.27 1.27)
						(thickness 0.15)
					)
					(justify left bottom)
					(hide yes)
				)
			)
			(property "License" "Apache-2.0"
				(at 20.32 -22.86 0)
				(effects
					(font
						(size 1.27 1.27)
						(thickness 0.15)
					)
					(justify left bottom)
					(hide yes)
				)
			)
			(property "Author" "Antmicro"
				(at 20.32 -25.4 0)
				(effects
					(font
						(size 1.27 1.27)
						(thickness 0.15)
					)
					(justify left bottom)
					(hide yes)
				)
			)
			(property "Val" "4u7"
				(at 20.32 -7.62 0)
				(effects
					(font
						(size 1.27 1.27)
						(thickness 0.15)
					)
					(justify left bottom)
				)
			)
			(property "Voltage" ""
				(at 20.32 -27.94 0)
				(effects
					(font
						(size 1.27 1.27)
					)
					(justify left bottom)
					(hide yes)
				)
			)
			(property "Dielectric" ""
				(at 20.32 -30.48 0)
				(effects
					(font
						(size 1.27 1.27)
					)
					(justify left bottom)
					(hide yes)
				)
			)
			(symbol "C_4u7_0402_0_1"
				(polyline
					(pts
						(xy 2.032 -1.524) (xy 2.032 1.524)
					)
					(stroke
						(width 0.3048)
						(type default)
					)
					(fill
						(type none)
					)
				)
				(polyline
					(pts
						(xy 3.048 -1.524) (xy 3.048 1.524)
					)
					(stroke
						(width 0.3302)
						(type default)
					)
					(fill
						(type none)
					)
				)
			)
			(symbol "C_4u7_0402_1_1"
				(pin passive line
					(at 0 0 0)
					(length 2.032)
					(name "~"
						(effects
							(font
								(size 1.27 1.27)
							)
						)
					)
					(number "1"
						(effects
							(font
								(size 1.27 1.27)
							)
						)
					)
				)
				(pin passive line
					(at 5.08 0 180)
					(length 2.032)
					(name "~"
						(effects
							(font
								(size 1.27 1.27)
							)
						)
					)
					(number "2"
						(effects
							(font
								(size 1.27 1.27)
							)
						)
					)
				)
			)
		)
	(symbol "antmicroCapacitorsmisc:C_100n_0201"
			(pin_numbers
				(hide yes)
			)
			(pin_names
				(hide yes)
			)
			(exclude_from_sim no)
			(in_bom yes)
			(on_board yes)
			(property "Reference" "C"
				(at 20.32 -5.08 0)
				(effects
					(font
						(size 1.27 1.27)
						(thickness 0.15)
					)
					(justify left bottom)
				)
			)
			(property "Value" "C_100n_0201"
				(at 20.32 -10.16 0)
				(effects
					(font
						(size 1.27 1.27)
						(thickness 0.15)
					)
					(justify left bottom)
					(hide yes)
				)
			)
			(property "Footprint" "antmicro-footprints:C_0201"
				(at 20.32 -12.7 0)
				(effects
					(font
						(size 1.27 1.27)
						(thickness 0.15)
					)
					(justify left bottom)
					(hide yes)
				)
			)
			(property "Datasheet" "https://www.yageo.com/en/Chart/Download/pdf/CC0201KRX6S5BB104"
				(at 20.32 -15.24 0)
				(effects
					(font
						(size 1.27 1.27)
						(thickness 0.15)
					)
					(justify left bottom)
					(hide yes)
				)
			)
			(property "Description" "SMD Multilayer Ceramic Capacitor, 0.1 µF, 6.3 V, 0201 [0603 Metric], ± 10%, X6S, CC Series"
				(at 0 0 0)
				(effects
					(font
						(size 1.27 1.27)
					)
					(hide yes)
				)
			)
			(property "MPN" "CC0201KRX6S5BB104"
				(at 20.32 -17.78 0)
				(effects
					(font
						(size 1.27 1.27)
						(thickness 0.15)
					)
					(justify left bottom)
					(hide yes)
				)
			)
			(property "Manufacturer" "YAGEO"
				(at 20.32 -20.32 0)
				(effects
					(font
						(size 1.27 1.27)
						(thickness 0.15)
					)
					(justify left bottom)
					(hide yes)
				)
			)
			(property "License" "Apache-2.0"
				(at 20.32 -22.86 0)
				(effects
					(font
						(size 1.27 1.27)
						(thickness 0.15)
					)
					(justify left bottom)
					(hide yes)
				)
			)
			(property "Author" "Antmicro"
				(at 20.32 -25.4 0)
				(effects
					(font
						(size 1.27 1.27)
						(thickness 0.15)
					)
					(justify left bottom)
					(hide yes)
				)
			)
			(property "Val" "100n"
				(at 20.32 -7.62 0)
				(effects
					(font
						(size 1.27 1.27)
						(thickness 0.15)
					)
					(justify left bottom)
				)
			)
			(property "Voltage" ""
				(at 20.32 -27.94 0)
				(effects
					(font
						(size 1.27 1.27)
					)
					(justify left bottom)
					(hide yes)
				)
			)
			(property "Dielectric" ""
				(at 20.32 -30.48 0)
				(effects
					(font
						(size 1.27 1.27)
					)
					(justify left bottom)
					(hide yes)
				)
			)
			(property "Public" "False"
				(at 20.32 -33.02 0)
				(effects
					(font
						(size 1.27 1.27)
					)
					(justify left bottom)
					(hide yes)
				)
			)
			(property "ki_keywords" "0201, SMT, CAPACITOR, PASSIVE, MLCC, CERAMIC"
				(at 0 0 0)
				(effects
					(font
						(size 1.27 1.27)
					)
					(hide yes)
				)
			)
			(symbol "C_100n_0201_0_1"
				(polyline
					(pts
						(xy 2.032 -1.524) (xy 2.032 1.524)
					)
					(stroke
						(width 0.3048)
						(type default)
					)
					(fill
						(type none)
					)
				)
				(polyline
					(pts
						(xy 3.048 -1.524) (xy 3.048 1.524)
					)
					(stroke
						(width 0.3302)
						(type default)
					)
					(fill
						(type none)
					)
				)
			)
			(symbol "C_100n_0201_1_1"
				(pin passive line
					(at 0 0 0)
					(length 2.032)
					(name "~"
						(effects
							(font
								(size 1.27 1.27)
							)
						)
					)
					(number "1"
						(effects
							(font
								(size 1.27 1.27)
							)
						)
					)
				)
				(pin passive line
					(at 5.08 0 180)
					(length 2.032)
					(name "~"
						(effects
							(font
								(size 1.27 1.27)
							)
						)
					)
					(number "2"
						(effects
							(font
								(size 1.27 1.27)
							)
						)
					)
				)
			)
		)
	(symbol "antmicroDCDCConverters:TPS613221A_SOT-23-5"
			(exclude_from_sim no)
			(in_bom yes)
			(on_board yes)
			(property "Reference" "U"
				(at 33.02 -2.54 0)
				(effects
					(font
						(size 1.27 1.27)
						(thickness 0.15)
					)
					(justify left bottom)
				)
			)
			(property "Value" "TPS613221A_SOT-23-5"
				(at 33.02 -5.08 0)
				(effects
					(font
						(size 1.27 1.27)
						(thickness 0.15)
					)
					(justify left bottom)
					(hide yes)
				)
			)
			(property "Footprint" "antmicro-footprints:SOT-23-5"
				(at 33.02 -7.62 0)
				(effects
					(font
						(size 1.27 1.27)
						(thickness 0.15)
					)
					(justify left bottom)
					(hide yes)
				)
			)
			(property "Datasheet" "https://www.ti.com/lit/ds/symlink/tps61322.pdf?ts=1679307661323&ref_url=https%253A%252F%252Fwww.ti.com%252Fproduct%252FTPS61322%252Fpart-details%252FTPS613221ADBVT%253Futm_source%253Dgoogle%2526utm_medium%253Dcpc%2526utm_campaign%253Docb-tistore-promo-app_opn_en-cpc-storeic-google-wwe%2526utm_content%253DDevice%2526ds_k%253DTPS613221ADBVT%2526DCM%253Dyes%2526gclid%253DCjwKCAjwiOCgBhAgEiwAjv5whAbq73RvnAdgvLpW8LFuSFEla1kNqoJei2y0mTqS4-Xlc-1KWPDvLxoCIUoQAvD_BwE%2526gclsrc%253Daw.ds"
				(at 33.02 -10.16 0)
				(effects
					(font
						(size 1.27 1.27)
						(thickness 0.15)
					)
					(justify left bottom)
					(hide yes)
				)
			)
			(property "Description" "Synchronous Boost Step Up Regulator, Fixed, 0.9V to 5.5V In, 3.3V/1.2A Out, 1.6MHz, SOT-23-5"
				(at 0 0 0)
				(effects
					(font
						(size 1.27 1.27)
					)
					(hide yes)
				)
			)
			(property "Manufacturer" "Texas Instruments"
				(at 33.02 -12.7 0)
				(effects
					(font
						(size 1.27 1.27)
						(thickness 0.15)
					)
					(justify left bottom)
					(hide yes)
				)
			)
			(property "MPN" "TPS613221ADBVT"
				(at 33.02 -15.24 0)
				(effects
					(font
						(size 1.27 1.27)
						(thickness 0.15)
					)
					(justify left bottom)
				)
			)
			(property "Author" "Antmicro"
				(at 33.02 -17.78 0)
				(effects
					(font
						(size 1.27 1.27)
						(thickness 0.15)
					)
					(justify left bottom)
					(hide yes)
				)
			)
			(property "License" "Apache-2.0"
				(at 33.02 -20.32 0)
				(effects
					(font
						(size 1.27 1.27)
						(thickness 0.15)
					)
					(justify left bottom)
					(hide yes)
				)
			)
			(property "ki_keywords" "SMT, PMIC, IC, SWITCHING, VOLTAGE, REGULATOR, DC-DC"
				(at 0 0 0)
				(effects
					(font
						(size 1.27 1.27)
					)
					(hide yes)
				)
			)
			(property "ki_fp_filters" "DBV0005A_N DBV0005A_M DBV0005A_L"
				(at 0 0 0)
				(effects
					(font
						(size 1.27 1.27)
					)
					(hide yes)
				)
			)
			(symbol "TPS613221A_SOT-23-5_1_1"
				(rectangle
					(start 2.54 2.54)
					(end 12.7 -7.62)
					(stroke
						(width 0.254)
						(type default)
					)
					(fill
						(type background)
					)
				)
				(rectangle
					(start 12.7 -7.62)
					(end 12.7 -7.62)
					(stroke
						(width 0.254)
						(type default)
					)
					(fill
						(type background)
					)
				)
				(pin power_in line
					(at 0 0 0)
					(length 2.54)
					(name "SW"
						(effects
							(font
								(size 1.27 1.27)
							)
						)
					)
					(number "1"
						(effects
							(font
								(size 1.27 1.27)
							)
						)
					)
				)
				(pin no_connect line
					(at 2.54 -2.54 0)
					(length 2.54)
					(hide yes)
					(name "NC"
						(effects
							(font
								(size 1.27 1.27)
							)
						)
					)
					(number "3"
						(effects
							(font
								(size 1.27 1.27)
							)
						)
					)
				)
				(pin no_connect line
					(at 2.54 -5.08 0)
					(length 2.54)
					(hide yes)
					(name "NC"
						(effects
							(font
								(size 1.27 1.27)
							)
						)
					)
					(number "5"
						(effects
							(font
								(size 1.27 1.27)
							)
						)
					)
				)
				(pin power_in line
					(at 15.24 0 180)
					(length 2.54)
					(name "VOUT"
						(effects
							(font
								(size 1.27 1.27)
							)
						)
					)
					(number "4"
						(effects
							(font
								(size 1.27 1.27)
							)
						)
					)
				)
				(pin power_in line
					(at 15.24 -5.08 180)
					(length 2.54)
					(name "GND"
						(effects
							(font
								(size 1.27 1.27)
							)
						)
					)
					(number "2"
						(effects
							(font
								(size 1.27 1.27)
							)
						)
					)
				)
			)
		)
	(symbol "antmicroEdgeConnectors:PCB-Edge_SODIMM_2x130_DDR4"
			(exclude_from_sim no)
			(in_bom no)
			(on_board yes)
			(property "Reference" "J"
				(at 36.83 0 0)
				(effects
					(font
						(size 1.27 1.27)
						(thickness 0.15)
					)
					(justify left bottom)
				)
			)
			(property "Value" "PCB-Edge_SODIMM_2x130_DDR4"
				(at 36.83 -2.54 0)
				(effects
					(font
						(size 1.27 1.27)
						(thickness 0.15)
					)
					(justify left bottom)
				)
			)
			(property "Footprint" "antmicro-footprints:PCB-Edge_SODIMM_2x130_DDR4"
				(at 36.83 -5.08 0)
				(effects
					(font
						(size 1.27 1.27)
						(thickness 0.15)
					)
					(justify left bottom)
					(hide yes)
				)
			)
			(property "Datasheet" ""
				(at 36.83 -12.7 0)
				(effects
					(font
						(size 1.27 1.27)
						(thickness 0.15)
					)
					(justify left bottom)
					(hide yes)
				)
			)
			(property "Description" "DDR SO-DIMM PCB Edge"
				(at 0 0 0)
				(effects
					(font
						(size 1.27 1.27)
					)
					(hide yes)
				)
			)
			(property "MPN" ""
				(at 36.83 -6.35 0)
				(effects
					(font
						(size 1.27 1.27)
					)
					(justify left)
					(hide yes)
				)
			)
			(property "Manufacturer" ""
				(at 36.83 -8.89 0)
				(effects
					(font
						(size 1.27 1.27)
					)
					(justify left)
					(hide yes)
				)
			)
			(property "Author" "Antmicro"
				(at 36.83 -15.24 0)
				(effects
					(font
						(size 1.27 1.27)
						(thickness 0.15)
					)
					(justify left bottom)
					(hide yes)
				)
			)
			(property "License" "Apache-2.0"
				(at 36.83 -17.78 0)
				(effects
					(font
						(size 1.27 1.27)
						(thickness 0.15)
					)
					(justify left bottom)
					(hide yes)
				)
			)
			(property "Public" "False"
				(at 36.83 -20.32 0)
				(effects
					(font
						(size 1.27 1.27)
					)
					(justify left bottom)
					(hide yes)
				)
			)
			(property "ki_locked" ""
				(at 0 0 0)
				(effects
					(font
						(size 1.27 1.27)
					)
				)
			)
			(property "ki_keywords" "EDGE, CONNECTOR"
				(at 0 0 0)
				(effects
					(font
						(size 1.27 1.27)
					)
					(hide yes)
				)
			)
			(symbol "PCB-Edge_SODIMM_2x130_DDR4_1_1"
				(rectangle
					(start 3.81 2.54)
					(end 19.05 -165.1)
					(stroke
						(width 0.254)
						(type default)
					)
					(fill
						(type background)
					)
				)
				(pin passive line
					(at 0 0 0)
					(length 3.81)
					(name "1"
						(effects
							(font
								(size 1.27 1.27)
							)
						)
					)
					(number "1"
						(effects
							(font
								(size 1.27 1.27)
							)
						)
					)
				)
				(pin passive line
					(at 0 -2.54 0)
					(length 3.81)
					(name "3"
						(effects
							(font
								(size 1.27 1.27)
							)
						)
					)
					(number "3"
						(effects
							(font
								(size 1.27 1.27)
							)
						)
					)
				)
				(pin passive line
					(at 0 -5.08 0)
					(length 3.81)
					(name "5"
						(effects
							(font
								(size 1.27 1.27)
							)
						)
					)
					(number "5"
						(effects
							(font
								(size 1.27 1.27)
							)
						)
					)
				)
				(pin passive line
					(at 0 -7.62 0)
					(length 3.81)
					(name "7"
						(effects
							(font
								(size 1.27 1.27)
							)
						)
					)
					(number "7"
						(effects
							(font
								(size 1.27 1.27)
							)
						)
					)
				)
				(pin passive line
					(at 0 -10.16 0)
					(length 3.81)
					(name "9"
						(effects
							(font
								(size 1.27 1.27)
							)
						)
					)
					(number "9"
						(effects
							(font
								(size 1.27 1.27)
							)
						)
					)
				)
				(pin passive line
					(at 0 -12.7 0)
					(length 3.81)
					(name "11"
						(effects
							(font
								(size 1.27 1.27)
							)
						)
					)
					(number "11"
						(effects
							(font
								(size 1.27 1.27)
							)
						)
					)
				)
				(pin passive line
					(at 0 -15.24 0)
					(length 3.81)
					(name "13"
						(effects
							(font
								(size 1.27 1.27)
							)
						)
					)
					(number "13"
						(effects
							(font
								(size 1.27 1.27)
							)
						)
					)
				)
				(pin passive line
					(at 0 -17.78 0)
					(length 3.81)
					(name "15"
						(effects
							(font
								(size 1.27 1.27)
							)
						)
					)
					(number "15"
						(effects
							(font
								(size 1.27 1.27)
							)
						)
					)
				)
				(pin passive line
					(at 0 -20.32 0)
					(length 3.81)
					(name "17"
						(effects
							(font
								(size 1.27 1.27)
							)
						)
					)
					(number "17"
						(effects
							(font
								(size 1.27 1.27)
							)
						)
					)
				)
				(pin passive line
					(at 0 -22.86 0)
					(length 3.81)
					(name "19"
						(effects
							(font
								(size 1.27 1.27)
							)
						)
					)
					(number "19"
						(effects
							(font
								(size 1.27 1.27)
							)
						)
					)
				)
				(pin passive line
					(at 0 -25.4 0)
					(length 3.81)
					(name "21"
						(effects
							(font
								(size 1.27 1.27)
							)
						)
					)
					(number "21"
						(effects
							(font
								(size 1.27 1.27)
							)
						)
					)
				)
				(pin passive line
					(at 0 -27.94 0)
					(length 3.81)
					(name "23"
						(effects
							(font
								(size 1.27 1.27)
							)
						)
					)
					(number "23"
						(effects
							(font
								(size 1.27 1.27)
							)
						)
					)
				)
				(pin passive line
					(at 0 -30.48 0)
					(length 3.81)
					(name "25"
						(effects
							(font
								(size 1.27 1.27)
							)
						)
					)
					(number "25"
						(effects
							(font
								(size 1.27 1.27)
							)
						)
					)
				)
				(pin passive line
					(at 0 -33.02 0)
					(length 3.81)
					(name "27"
						(effects
							(font
								(size 1.27 1.27)
							)
						)
					)
					(number "27"
						(effects
							(font
								(size 1.27 1.27)
							)
						)
					)
				)
				(pin passive line
					(at 0 -35.56 0)
					(length 3.81)
					(name "29"
						(effects
							(font
								(size 1.27 1.27)
							)
						)
					)
					(number "29"
						(effects
							(font
								(size 1.27 1.27)
							)
						)
					)
				)
				(pin passive line
					(at 0 -38.1 0)
					(length 3.81)
					(name "31"
						(effects
							(font
								(size 1.27 1.27)
							)
						)
					)
					(number "31"
						(effects
							(font
								(size 1.27 1.27)
							)
						)
					)
				)
				(pin passive line
					(at 0 -40.64 0)
					(length 3.81)
					(name "33"
						(effects
							(font
								(size 1.27 1.27)
							)
						)
					)
					(number "33"
						(effects
							(font
								(size 1.27 1.27)
							)
						)
					)
				)
				(pin passive line
					(at 0 -43.18 0)
					(length 3.81)
					(name "35"
						(effects
							(font
								(size 1.27 1.27)
							)
						)
					)
					(number "35"
						(effects
							(font
								(size 1.27 1.27)
							)
						)
					)
				)
				(pin passive line
					(at 0 -45.72 0)
					(length 3.81)
					(name "37"
						(effects
							(font
								(size 1.27 1.27)
							)
						)
					)
					(number "37"
						(effects
							(font
								(size 1.27 1.27)
							)
						)
					)
				)
				(pin passive line
					(at 0 -48.26 0)
					(length 3.81)
					(name "39"
						(effects
							(font
								(size 1.27 1.27)
							)
						)
					)
					(number "39"
						(effects
							(font
								(size 1.27 1.27)
							)
						)
					)
				)
				(pin passive line
					(at 0 -50.8 0)
					(length 3.81)
					(name "41"
						(effects
							(font
								(size 1.27 1.27)
							)
						)
					)
					(number "41"
						(effects
							(font
								(size 1.27 1.27)
							)
						)
					)
				)
				(pin passive line
					(at 0 -53.34 0)
					(length 3.81)
					(name "43"
						(effects
							(font
								(size 1.27 1.27)
							)
						)
					)
					(number "43"
						(effects
							(font
								(size 1.27 1.27)
							)
						)
					)
				)
				(pin passive line
					(at 0 -55.88 0)
					(length 3.81)
					(name "45"
						(effects
							(font
								(size 1.27 1.27)
							)
						)
					)
					(number "45"
						(effects
							(font
								(size 1.27 1.27)
							)
						)
					)
				)
				(pin passive line
					(at 0 -58.42 0)
					(length 3.81)
					(name "47"
						(effects
							(font
								(size 1.27 1.27)
							)
						)
					)
					(number "47"
						(effects
							(font
								(size 1.27 1.27)
							)
						)
					)
				)
				(pin passive line
					(at 0 -60.96 0)
					(length 3.81)
					(name "49"
						(effects
							(font
								(size 1.27 1.27)
							)
						)
					)
					(number "49"
						(effects
							(font
								(size 1.27 1.27)
							)
						)
					)
				)
				(pin passive line
					(at 0 -63.5 0)
					(length 3.81)
					(name "51"
						(effects
							(font
								(size 1.27 1.27)
							)
						)
					)
					(number "51"
						(effects
							(font
								(size 1.27 1.27)
							)
						)
					)
				)
				(pin passive line
					(at 0 -66.04 0)
					(length 3.81)
					(name "53"
						(effects
							(font
								(size 1.27 1.27)
							)
						)
					)
					(number "53"
						(effects
							(font
								(size 1.27 1.27)
							)
						)
					)
				)
				(pin passive line
					(at 0 -68.58 0)
					(length 3.81)
					(name "55"
						(effects
							(font
								(size 1.27 1.27)
							)
						)
					)
					(number "55"
						(effects
							(font
								(size 1.27 1.27)
							)
						)
					)
				)
				(pin passive line
					(at 0 -71.12 0)
					(length 3.81)
					(name "57"
						(effects
							(font
								(size 1.27 1.27)
							)
						)
					)
					(number "57"
						(effects
							(font
								(size 1.27 1.27)
							)
						)
					)
				)
				(pin passive line
					(at 0 -73.66 0)
					(length 3.81)
					(name "59"
						(effects
							(font
								(size 1.27 1.27)
							)
						)
					)
					(number "59"
						(effects
							(font
								(size 1.27 1.27)
							)
						)
					)
				)
				(pin passive line
					(at 0 -76.2 0)
					(length 3.81)
					(name "61"
						(effects
							(font
								(size 1.27 1.27)
							)
						)
					)
					(number "61"
						(effects
							(font
								(size 1.27 1.27)
							)
						)
					)
				)
				(pin passive line
					(at 0 -78.74 0)
					(length 3.81)
					(name "63"
						(effects
							(font
								(size 1.27 1.27)
							)
						)
					)
					(number "63"
						(effects
							(font
								(size 1.27 1.27)
							)
						)
					)
				)
				(pin passive line
					(at 0 -81.28 0)
					(length 3.81)
					(name "65"
						(effects
							(font
								(size 1.27 1.27)
							)
						)
					)
					(number "65"
						(effects
							(font
								(size 1.27 1.27)
							)
						)
					)
				)
				(pin passive line
					(at 0 -83.82 0)
					(length 3.81)
					(name "67"
						(effects
							(font
								(size 1.27 1.27)
							)
						)
					)
					(number "67"
						(effects
							(font
								(size 1.27 1.27)
							)
						)
					)
				)
				(pin passive line
					(at 0 -86.36 0)
					(length 3.81)
					(name "69"
						(effects
							(font
								(size 1.27 1.27)
							)
						)
					)
					(number "69"
						(effects
							(font
								(size 1.27 1.27)
							)
						)
					)
				)
				(pin passive line
					(at 0 -88.9 0)
					(length 3.81)
					(name "71"
						(effects
							(font
								(size 1.27 1.27)
							)
						)
					)
					(number "71"
						(effects
							(font
								(size 1.27 1.27)
							)
						)
					)
				)
				(pin passive line
					(at 0 -91.44 0)
					(length 3.81)
					(name "73"
						(effects
							(font
								(size 1.27 1.27)
							)
						)
					)
					(number "73"
						(effects
							(font
								(size 1.27 1.27)
							)
						)
					)
				)
				(pin passive line
					(at 0 -93.98 0)
					(length 3.81)
					(name "75"
						(effects
							(font
								(size 1.27 1.27)
							)
						)
					)
					(number "75"
						(effects
							(font
								(size 1.27 1.27)
							)
						)
					)
				)
				(pin passive line
					(at 0 -96.52 0)
					(length 3.81)
					(name "77"
						(effects
							(font
								(size 1.27 1.27)
							)
						)
					)
					(number "77"
						(effects
							(font
								(size 1.27 1.27)
							)
						)
					)
				)
				(pin passive line
					(at 0 -99.06 0)
					(length 3.81)
					(name "79"
						(effects
							(font
								(size 1.27 1.27)
							)
						)
					)
					(number "79"
						(effects
							(font
								(size 1.27 1.27)
							)
						)
					)
				)
				(pin passive line
					(at 0 -101.6 0)
					(length 3.81)
					(name "81"
						(effects
							(font
								(size 1.27 1.27)
							)
						)
					)
					(number "81"
						(effects
							(font
								(size 1.27 1.27)
							)
						)
					)
				)
				(pin passive line
					(at 0 -104.14 0)
					(length 3.81)
					(name "83"
						(effects
							(font
								(size 1.27 1.27)
							)
						)
					)
					(number "83"
						(effects
							(font
								(size 1.27 1.27)
							)
						)
					)
				)
				(pin passive line
					(at 0 -106.68 0)
					(length 3.81)
					(name "85"
						(effects
							(font
								(size 1.27 1.27)
							)
						)
					)
					(number "85"
						(effects
							(font
								(size 1.27 1.27)
							)
						)
					)
				)
				(pin passive line
					(at 0 -109.22 0)
					(length 3.81)
					(name "87"
						(effects
							(font
								(size 1.27 1.27)
							)
						)
					)
					(number "87"
						(effects
							(font
								(size 1.27 1.27)
							)
						)
					)
				)
				(pin passive line
					(at 0 -111.76 0)
					(length 3.81)
					(name "89"
						(effects
							(font
								(size 1.27 1.27)
							)
						)
					)
					(number "89"
						(effects
							(font
								(size 1.27 1.27)
							)
						)
					)
				)
				(pin passive line
					(at 0 -114.3 0)
					(length 3.81)
					(name "91"
						(effects
							(font
								(size 1.27 1.27)
							)
						)
					)
					(number "91"
						(effects
							(font
								(size 1.27 1.27)
							)
						)
					)
				)
				(pin passive line
					(at 0 -116.84 0)
					(length 3.81)
					(name "93"
						(effects
							(font
								(size 1.27 1.27)
							)
						)
					)
					(number "93"
						(effects
							(font
								(size 1.27 1.27)
							)
						)
					)
				)
				(pin passive line
					(at 0 -119.38 0)
					(length 3.81)
					(name "95"
						(effects
							(font
								(size 1.27 1.27)
							)
						)
					)
					(number "95"
						(effects
							(font
								(size 1.27 1.27)
							)
						)
					)
				)
				(pin passive line
					(at 0 -121.92 0)
					(length 3.81)
					(name "97"
						(effects
							(font
								(size 1.27 1.27)
							)
						)
					)
					(number "97"
						(effects
							(font
								(size 1.27 1.27)
							)
						)
					)
				)
				(pin passive line
					(at 0 -124.46 0)
					(length 3.81)
					(name "99"
						(effects
							(font
								(size 1.27 1.27)
							)
						)
					)
					(number "99"
						(effects
							(font
								(size 1.27 1.27)
							)
						)
					)
				)
				(pin passive line
					(at 0 -127 0)
					(length 3.81)
					(name "101"
						(effects
							(font
								(size 1.27 1.27)
							)
						)
					)
					(number "101"
						(effects
							(font
								(size 1.27 1.27)
							)
						)
					)
				)
				(pin passive line
					(at 0 -129.54 0)
					(length 3.81)
					(name "103"
						(effects
							(font
								(size 1.27 1.27)
							)
						)
					)
					(number "103"
						(effects
							(font
								(size 1.27 1.27)
							)
						)
					)
				)
				(pin passive line
					(at 0 -132.08 0)
					(length 3.81)
					(name "105"
						(effects
							(font
								(size 1.27 1.27)
							)
						)
					)
					(number "105"
						(effects
							(font
								(size 1.27 1.27)
							)
						)
					)
				)
				(pin passive line
					(at 0 -134.62 0)
					(length 3.81)
					(name "107"
						(effects
							(font
								(size 1.27 1.27)
							)
						)
					)
					(number "107"
						(effects
							(font
								(size 1.27 1.27)
							)
						)
					)
				)
				(pin passive line
					(at 0 -137.16 0)
					(length 3.81)
					(name "109"
						(effects
							(font
								(size 1.27 1.27)
							)
						)
					)
					(number "109"
						(effects
							(font
								(size 1.27 1.27)
							)
						)
					)
				)
				(pin passive line
					(at 0 -139.7 0)
					(length 3.81)
					(name "111"
						(effects
							(font
								(size 1.27 1.27)
							)
						)
					)
					(number "111"
						(effects
							(font
								(size 1.27 1.27)
							)
						)
					)
				)
				(pin passive line
					(at 0 -142.24 0)
					(length 3.81)
					(name "113"
						(effects
							(font
								(size 1.27 1.27)
							)
						)
					)
					(number "113"
						(effects
							(font
								(size 1.27 1.27)
							)
						)
					)
				)
				(pin passive line
					(at 0 -144.78 0)
					(length 3.81)
					(name "115"
						(effects
							(font
								(size 1.27 1.27)
							)
						)
					)
					(number "115"
						(effects
							(font
								(size 1.27 1.27)
							)
						)
					)
				)
				(pin passive line
					(at 0 -147.32 0)
					(length 3.81)
					(name "117"
						(effects
							(font
								(size 1.27 1.27)
							)
						)
					)
					(number "117"
						(effects
							(font
								(size 1.27 1.27)
							)
						)
					)
				)
				(pin passive line
					(at 0 -149.86 0)
					(length 3.81)
					(name "119"
						(effects
							(font
								(size 1.27 1.27)
							)
						)
					)
					(number "119"
						(effects
							(font
								(size 1.27 1.27)
							)
						)
					)
				)
				(pin passive line
					(at 0 -152.4 0)
					(length 3.81)
					(name "121"
						(effects
							(font
								(size 1.27 1.27)
							)
						)
					)
					(number "121"
						(effects
							(font
								(size 1.27 1.27)
							)
						)
					)
				)
				(pin passive line
					(at 0 -154.94 0)
					(length 3.81)
					(name "123"
						(effects
							(font
								(size 1.27 1.27)
							)
						)
					)
					(number "123"
						(effects
							(font
								(size 1.27 1.27)
							)
						)
					)
				)
				(pin passive line
					(at 0 -157.48 0)
					(length 3.81)
					(name "125"
						(effects
							(font
								(size 1.27 1.27)
							)
						)
					)
					(number "125"
						(effects
							(font
								(size 1.27 1.27)
							)
						)
					)
				)
				(pin passive line
					(at 0 -160.02 0)
					(length 3.81)
					(name "127"
						(effects
							(font
								(size 1.27 1.27)
							)
						)
					)
					(number "127"
						(effects
							(font
								(size 1.27 1.27)
							)
						)
					)
				)
				(pin passive line
					(at 0 -162.56 0)
					(length 3.81)
					(name "129"
						(effects
							(font
								(size 1.27 1.27)
							)
						)
					)
					(number "129"
						(effects
							(font
								(size 1.27 1.27)
							)
						)
					)
				)
				(pin passive line
					(at 22.86 0 180)
					(length 3.81)
					(name "2"
						(effects
							(font
								(size 1.27 1.27)
							)
						)
					)
					(number "2"
						(effects
							(font
								(size 1.27 1.27)
							)
						)
					)
				)
				(pin passive line
					(at 22.86 -2.54 180)
					(length 3.81)
					(name "4"
						(effects
							(font
								(size 1.27 1.27)
							)
						)
					)
					(number "4"
						(effects
							(font
								(size 1.27 1.27)
							)
						)
					)
				)
				(pin passive line
					(at 22.86 -5.08 180)
					(length 3.81)
					(name "6"
						(effects
							(font
								(size 1.27 1.27)
							)
						)
					)
					(number "6"
						(effects
							(font
								(size 1.27 1.27)
							)
						)
					)
				)
				(pin passive line
					(at 22.86 -7.62 180)
					(length 3.81)
					(name "8"
						(effects
							(font
								(size 1.27 1.27)
							)
						)
					)
					(number "8"
						(effects
							(font
								(size 1.27 1.27)
							)
						)
					)
				)
				(pin passive line
					(at 22.86 -10.16 180)
					(length 3.81)
					(name "10"
						(effects
							(font
								(size 1.27 1.27)
							)
						)
					)
					(number "10"
						(effects
							(font
								(size 1.27 1.27)
							)
						)
					)
				)
				(pin passive line
					(at 22.86 -12.7 180)
					(length 3.81)
					(name "12"
						(effects
							(font
								(size 1.27 1.27)
							)
						)
					)
					(number "12"
						(effects
							(font
								(size 1.27 1.27)
							)
						)
					)
				)
				(pin passive line
					(at 22.86 -15.24 180)
					(length 3.81)
					(name "14"
						(effects
							(font
								(size 1.27 1.27)
							)
						)
					)
					(number "14"
						(effects
							(font
								(size 1.27 1.27)
							)
						)
					)
				)
				(pin passive line
					(at 22.86 -17.78 180)
					(length 3.81)
					(name "16"
						(effects
							(font
								(size 1.27 1.27)
							)
						)
					)
					(number "16"
						(effects
							(font
								(size 1.27 1.27)
							)
						)
					)
				)
				(pin passive line
					(at 22.86 -20.32 180)
					(length 3.81)
					(name "18"
						(effects
							(font
								(size 1.27 1.27)
							)
						)
					)
					(number "18"
						(effects
							(font
								(size 1.27 1.27)
							)
						)
					)
				)
				(pin passive line
					(at 22.86 -22.86 180)
					(length 3.81)
					(name "20"
						(effects
							(font
								(size 1.27 1.27)
							)
						)
					)
					(number "20"
						(effects
							(font
								(size 1.27 1.27)
							)
						)
					)
				)
				(pin passive line
					(at 22.86 -25.4 180)
					(length 3.81)
					(name "22"
						(effects
							(font
								(size 1.27 1.27)
							)
						)
					)
					(number "22"
						(effects
							(font
								(size 1.27 1.27)
							)
						)
					)
				)
				(pin passive line
					(at 22.86 -27.94 180)
					(length 3.81)
					(name "24"
						(effects
							(font
								(size 1.27 1.27)
							)
						)
					)
					(number "24"
						(effects
							(font
								(size 1.27 1.27)
							)
						)
					)
				)
				(pin passive line
					(at 22.86 -30.48 180)
					(length 3.81)
					(name "26"
						(effects
							(font
								(size 1.27 1.27)
							)
						)
					)
					(number "26"
						(effects
							(font
								(size 1.27 1.27)
							)
						)
					)
				)
				(pin passive line
					(at 22.86 -33.02 180)
					(length 3.81)
					(name "28"
						(effects
							(font
								(size 1.27 1.27)
							)
						)
					)
					(number "28"
						(effects
							(font
								(size 1.27 1.27)
							)
						)
					)
				)
				(pin passive line
					(at 22.86 -35.56 180)
					(length 3.81)
					(name "30"
						(effects
							(font
								(size 1.27 1.27)
							)
						)
					)
					(number "30"
						(effects
							(font
								(size 1.27 1.27)
							)
						)
					)
				)
				(pin passive line
					(at 22.86 -38.1 180)
					(length 3.81)
					(name "32"
						(effects
							(font
								(size 1.27 1.27)
							)
						)
					)
					(number "32"
						(effects
							(font
								(size 1.27 1.27)
							)
						)
					)
				)
				(pin passive line
					(at 22.86 -40.64 180)
					(length 3.81)
					(name "34"
						(effects
							(font
								(size 1.27 1.27)
							)
						)
					)
					(number "34"
						(effects
							(font
								(size 1.27 1.27)
							)
						)
					)
				)
				(pin passive line
					(at 22.86 -43.18 180)
					(length 3.81)
					(name "36"
						(effects
							(font
								(size 1.27 1.27)
							)
						)
					)
					(number "36"
						(effects
							(font
								(size 1.27 1.27)
							)
						)
					)
				)
				(pin passive line
					(at 22.86 -45.72 180)
					(length 3.81)
					(name "38"
						(effects
							(font
								(size 1.27 1.27)
							)
						)
					)
					(number "38"
						(effects
							(font
								(size 1.27 1.27)
							)
						)
					)
				)
				(pin passive line
					(at 22.86 -48.26 180)
					(length 3.81)
					(name "40"
						(effects
							(font
								(size 1.27 1.27)
							)
						)
					)
					(number "40"
						(effects
							(font
								(size 1.27 1.27)
							)
						)
					)
				)
				(pin passive line
					(at 22.86 -50.8 180)
					(length 3.81)
					(name "42"
						(effects
							(font
								(size 1.27 1.27)
							)
						)
					)
					(number "42"
						(effects
							(font
								(size 1.27 1.27)
							)
						)
					)
				)
				(pin passive line
					(at 22.86 -53.34 180)
					(length 3.81)
					(name "44"
						(effects
							(font
								(size 1.27 1.27)
							)
						)
					)
					(number "44"
						(effects
							(font
								(size 1.27 1.27)
							)
						)
					)
				)
				(pin passive line
					(at 22.86 -55.88 180)
					(length 3.81)
					(name "46"
						(effects
							(font
								(size 1.27 1.27)
							)
						)
					)
					(number "46"
						(effects
							(font
								(size 1.27 1.27)
							)
						)
					)
				)
				(pin passive line
					(at 22.86 -58.42 180)
					(length 3.81)
					(name "48"
						(effects
							(font
								(size 1.27 1.27)
							)
						)
					)
					(number "48"
						(effects
							(font
								(size 1.27 1.27)
							)
						)
					)
				)
				(pin passive line
					(at 22.86 -60.96 180)
					(length 3.81)
					(name "50"
						(effects
							(font
								(size 1.27 1.27)
							)
						)
					)
					(number "50"
						(effects
							(font
								(size 1.27 1.27)
							)
						)
					)
				)
				(pin passive line
					(at 22.86 -63.5 180)
					(length 3.81)
					(name "52"
						(effects
							(font
								(size 1.27 1.27)
							)
						)
					)
					(number "52"
						(effects
							(font
								(size 1.27 1.27)
							)
						)
					)
				)
				(pin passive line
					(at 22.86 -66.04 180)
					(length 3.81)
					(name "54"
						(effects
							(font
								(size 1.27 1.27)
							)
						)
					)
					(number "54"
						(effects
							(font
								(size 1.27 1.27)
							)
						)
					)
				)
				(pin passive line
					(at 22.86 -68.58 180)
					(length 3.81)
					(name "56"
						(effects
							(font
								(size 1.27 1.27)
							)
						)
					)
					(number "56"
						(effects
							(font
								(size 1.27 1.27)
							)
						)
					)
				)
				(pin passive line
					(at 22.86 -71.12 180)
					(length 3.81)
					(name "58"
						(effects
							(font
								(size 1.27 1.27)
							)
						)
					)
					(number "58"
						(effects
							(font
								(size 1.27 1.27)
							)
						)
					)
				)
				(pin passive line
					(at 22.86 -73.66 180)
					(length 3.81)
					(name "60"
						(effects
							(font
								(size 1.27 1.27)
							)
						)
					)
					(number "60"
						(effects
							(font
								(size 1.27 1.27)
							)
						)
					)
				)
				(pin passive line
					(at 22.86 -76.2 180)
					(length 3.81)
					(name "62"
						(effects
							(font
								(size 1.27 1.27)
							)
						)
					)
					(number "62"
						(effects
							(font
								(size 1.27 1.27)
							)
						)
					)
				)
				(pin passive line
					(at 22.86 -78.74 180)
					(length 3.81)
					(name "64"
						(effects
							(font
								(size 1.27 1.27)
							)
						)
					)
					(number "64"
						(effects
							(font
								(size 1.27 1.27)
							)
						)
					)
				)
				(pin passive line
					(at 22.86 -81.28 180)
					(length 3.81)
					(name "66"
						(effects
							(font
								(size 1.27 1.27)
							)
						)
					)
					(number "66"
						(effects
							(font
								(size 1.27 1.27)
							)
						)
					)
				)
				(pin passive line
					(at 22.86 -83.82 180)
					(length 3.81)
					(name "68"
						(effects
							(font
								(size 1.27 1.27)
							)
						)
					)
					(number "68"
						(effects
							(font
								(size 1.27 1.27)
							)
						)
					)
				)
				(pin passive line
					(at 22.86 -86.36 180)
					(length 3.81)
					(name "70"
						(effects
							(font
								(size 1.27 1.27)
							)
						)
					)
					(number "70"
						(effects
							(font
								(size 1.27 1.27)
							)
						)
					)
				)
				(pin passive line
					(at 22.86 -88.9 180)
					(length 3.81)
					(name "72"
						(effects
							(font
								(size 1.27 1.27)
							)
						)
					)
					(number "72"
						(effects
							(font
								(size 1.27 1.27)
							)
						)
					)
				)
				(pin passive line
					(at 22.86 -91.44 180)
					(length 3.81)
					(name "74"
						(effects
							(font
								(size 1.27 1.27)
							)
						)
					)
					(number "74"
						(effects
							(font
								(size 1.27 1.27)
							)
						)
					)
				)
				(pin passive line
					(at 22.86 -93.98 180)
					(length 3.81)
					(name "76"
						(effects
							(font
								(size 1.27 1.27)
							)
						)
					)
					(number "76"
						(effects
							(font
								(size 1.27 1.27)
							)
						)
					)
				)
				(pin passive line
					(at 22.86 -96.52 180)
					(length 3.81)
					(name "78"
						(effects
							(font
								(size 1.27 1.27)
							)
						)
					)
					(number "78"
						(effects
							(font
								(size 1.27 1.27)
							)
						)
					)
				)
				(pin passive line
					(at 22.86 -99.06 180)
					(length 3.81)
					(name "80"
						(effects
							(font
								(size 1.27 1.27)
							)
						)
					)
					(number "80"
						(effects
							(font
								(size 1.27 1.27)
							)
						)
					)
				)
				(pin passive line
					(at 22.86 -101.6 180)
					(length 3.81)
					(name "82"
						(effects
							(font
								(size 1.27 1.27)
							)
						)
					)
					(number "82"
						(effects
							(font
								(size 1.27 1.27)
							)
						)
					)
				)
				(pin passive line
					(at 22.86 -104.14 180)
					(length 3.81)
					(name "84"
						(effects
							(font
								(size 1.27 1.27)
							)
						)
					)
					(number "84"
						(effects
							(font
								(size 1.27 1.27)
							)
						)
					)
				)
				(pin passive line
					(at 22.86 -106.68 180)
					(length 3.81)
					(name "86"
						(effects
							(font
								(size 1.27 1.27)
							)
						)
					)
					(number "86"
						(effects
							(font
								(size 1.27 1.27)
							)
						)
					)
				)
				(pin passive line
					(at 22.86 -109.22 180)
					(length 3.81)
					(name "88"
						(effects
							(font
								(size 1.27 1.27)
							)
						)
					)
					(number "88"
						(effects
							(font
								(size 1.27 1.27)
							)
						)
					)
				)
				(pin passive line
					(at 22.86 -111.76 180)
					(length 3.81)
					(name "90"
						(effects
							(font
								(size 1.27 1.27)
							)
						)
					)
					(number "90"
						(effects
							(font
								(size 1.27 1.27)
							)
						)
					)
				)
				(pin passive line
					(at 22.86 -114.3 180)
					(length 3.81)
					(name "92"
						(effects
							(font
								(size 1.27 1.27)
							)
						)
					)
					(number "92"
						(effects
							(font
								(size 1.27 1.27)
							)
						)
					)
				)
				(pin passive line
					(at 22.86 -116.84 180)
					(length 3.81)
					(name "94"
						(effects
							(font
								(size 1.27 1.27)
							)
						)
					)
					(number "94"
						(effects
							(font
								(size 1.27 1.27)
							)
						)
					)
				)
				(pin passive line
					(at 22.86 -119.38 180)
					(length 3.81)
					(name "96"
						(effects
							(font
								(size 1.27 1.27)
							)
						)
					)
					(number "96"
						(effects
							(font
								(size 1.27 1.27)
							)
						)
					)
				)
				(pin passive line
					(at 22.86 -121.92 180)
					(length 3.81)
					(name "98"
						(effects
							(font
								(size 1.27 1.27)
							)
						)
					)
					(number "98"
						(effects
							(font
								(size 1.27 1.27)
							)
						)
					)
				)
				(pin passive line
					(at 22.86 -124.46 180)
					(length 3.81)
					(name "100"
						(effects
							(font
								(size 1.27 1.27)
							)
						)
					)
					(number "100"
						(effects
							(font
								(size 1.27 1.27)
							)
						)
					)
				)
				(pin passive line
					(at 22.86 -127 180)
					(length 3.81)
					(name "102"
						(effects
							(font
								(size 1.27 1.27)
							)
						)
					)
					(number "102"
						(effects
							(font
								(size 1.27 1.27)
							)
						)
					)
				)
				(pin passive line
					(at 22.86 -129.54 180)
					(length 3.81)
					(name "104"
						(effects
							(font
								(size 1.27 1.27)
							)
						)
					)
					(number "104"
						(effects
							(font
								(size 1.27 1.27)
							)
						)
					)
				)
				(pin passive line
					(at 22.86 -132.08 180)
					(length 3.81)
					(name "106"
						(effects
							(font
								(size 1.27 1.27)
							)
						)
					)
					(number "106"
						(effects
							(font
								(size 1.27 1.27)
							)
						)
					)
				)
				(pin passive line
					(at 22.86 -134.62 180)
					(length 3.81)
					(name "108"
						(effects
							(font
								(size 1.27 1.27)
							)
						)
					)
					(number "108"
						(effects
							(font
								(size 1.27 1.27)
							)
						)
					)
				)
				(pin passive line
					(at 22.86 -137.16 180)
					(length 3.81)
					(name "110"
						(effects
							(font
								(size 1.27 1.27)
							)
						)
					)
					(number "110"
						(effects
							(font
								(size 1.27 1.27)
							)
						)
					)
				)
				(pin passive line
					(at 22.86 -139.7 180)
					(length 3.81)
					(name "112"
						(effects
							(font
								(size 1.27 1.27)
							)
						)
					)
					(number "112"
						(effects
							(font
								(size 1.27 1.27)
							)
						)
					)
				)
				(pin passive line
					(at 22.86 -142.24 180)
					(length 3.81)
					(name "114"
						(effects
							(font
								(size 1.27 1.27)
							)
						)
					)
					(number "114"
						(effects
							(font
								(size 1.27 1.27)
							)
						)
					)
				)
				(pin passive line
					(at 22.86 -144.78 180)
					(length 3.81)
					(name "116"
						(effects
							(font
								(size 1.27 1.27)
							)
						)
					)
					(number "116"
						(effects
							(font
								(size 1.27 1.27)
							)
						)
					)
				)
				(pin passive line
					(at 22.86 -147.32 180)
					(length 3.81)
					(name "118"
						(effects
							(font
								(size 1.27 1.27)
							)
						)
					)
					(number "118"
						(effects
							(font
								(size 1.27 1.27)
							)
						)
					)
				)
				(pin passive line
					(at 22.86 -149.86 180)
					(length 3.81)
					(name "120"
						(effects
							(font
								(size 1.27 1.27)
							)
						)
					)
					(number "120"
						(effects
							(font
								(size 1.27 1.27)
							)
						)
					)
				)
				(pin passive line
					(at 22.86 -152.4 180)
					(length 3.81)
					(name "122"
						(effects
							(font
								(size 1.27 1.27)
							)
						)
					)
					(number "122"
						(effects
							(font
								(size 1.27 1.27)
							)
						)
					)
				)
				(pin passive line
					(at 22.86 -154.94 180)
					(length 3.81)
					(name "124"
						(effects
							(font
								(size 1.27 1.27)
							)
						)
					)
					(number "124"
						(effects
							(font
								(size 1.27 1.27)
							)
						)
					)
				)
				(pin passive line
					(at 22.86 -157.48 180)
					(length 3.81)
					(name "126"
						(effects
							(font
								(size 1.27 1.27)
							)
						)
					)
					(number "126"
						(effects
							(font
								(size 1.27 1.27)
							)
						)
					)
				)
				(pin passive line
					(at 22.86 -160.02 180)
					(length 3.81)
					(name "128"
						(effects
							(font
								(size 1.27 1.27)
							)
						)
					)
					(number "128"
						(effects
							(font
								(size 1.27 1.27)
							)
						)
					)
				)
				(pin passive line
					(at 22.86 -162.56 180)
					(length 3.81)
					(name "130"
						(effects
							(font
								(size 1.27 1.27)
							)
						)
					)
					(number "130"
						(effects
							(font
								(size 1.27 1.27)
							)
						)
					)
				)
			)
			(symbol "PCB-Edge_SODIMM_2x130_DDR4_2_1"
				(rectangle
					(start 3.81 2.54)
					(end 19.05 -165.1)
					(stroke
						(width 0.254)
						(type default)
					)
					(fill
						(type background)
					)
				)
				(polyline
					(pts
						(xy 3.81 -165.1) (xy 19.05 -165.1)
					)
					(stroke
						(width 0.254)
						(type default)
					)
					(fill
						(type background)
					)
				)
				(pin passive line
					(at 0 0 0)
					(length 3.81)
					(name "131"
						(effects
							(font
								(size 1.27 1.27)
							)
						)
					)
					(number "131"
						(effects
							(font
								(size 1.27 1.27)
							)
						)
					)
				)
				(pin passive line
					(at 0 -2.54 0)
					(length 3.81)
					(name "133"
						(effects
							(font
								(size 1.27 1.27)
							)
						)
					)
					(number "133"
						(effects
							(font
								(size 1.27 1.27)
							)
						)
					)
				)
				(pin passive line
					(at 0 -5.08 0)
					(length 3.81)
					(name "135"
						(effects
							(font
								(size 1.27 1.27)
							)
						)
					)
					(number "135"
						(effects
							(font
								(size 1.27 1.27)
							)
						)
					)
				)
				(pin passive line
					(at 0 -7.62 0)
					(length 3.81)
					(name "137"
						(effects
							(font
								(size 1.27 1.27)
							)
						)
					)
					(number "137"
						(effects
							(font
								(size 1.27 1.27)
							)
						)
					)
				)
				(pin passive line
					(at 0 -10.16 0)
					(length 3.81)
					(name "139"
						(effects
							(font
								(size 1.27 1.27)
							)
						)
					)
					(number "139"
						(effects
							(font
								(size 1.27 1.27)
							)
						)
					)
				)
				(pin passive line
					(at 0 -12.7 0)
					(length 3.81)
					(name "141"
						(effects
							(font
								(size 1.27 1.27)
							)
						)
					)
					(number "141"
						(effects
							(font
								(size 1.27 1.27)
							)
						)
					)
				)
				(pin passive line
					(at 0 -15.24 0)
					(length 3.81)
					(name "143"
						(effects
							(font
								(size 1.27 1.27)
							)
						)
					)
					(number "143"
						(effects
							(font
								(size 1.27 1.27)
							)
						)
					)
				)
				(pin passive line
					(at 0 -17.78 0)
					(length 3.81)
					(name "145"
						(effects
							(font
								(size 1.27 1.27)
							)
						)
					)
					(number "145"
						(effects
							(font
								(size 1.27 1.27)
							)
						)
					)
				)
				(pin passive line
					(at 0 -20.32 0)
					(length 3.81)
					(name "147"
						(effects
							(font
								(size 1.27 1.27)
							)
						)
					)
					(number "147"
						(effects
							(font
								(size 1.27 1.27)
							)
						)
					)
				)
				(pin passive line
					(at 0 -22.86 0)
					(length 3.81)
					(name "149"
						(effects
							(font
								(size 1.27 1.27)
							)
						)
					)
					(number "149"
						(effects
							(font
								(size 1.27 1.27)
							)
						)
					)
				)
				(pin passive line
					(at 0 -25.4 0)
					(length 3.81)
					(name "151"
						(effects
							(font
								(size 1.27 1.27)
							)
						)
					)
					(number "151"
						(effects
							(font
								(size 1.27 1.27)
							)
						)
					)
				)
				(pin passive line
					(at 0 -27.94 0)
					(length 3.81)
					(name "153"
						(effects
							(font
								(size 1.27 1.27)
							)
						)
					)
					(number "153"
						(effects
							(font
								(size 1.27 1.27)
							)
						)
					)
				)
				(pin passive line
					(at 0 -30.48 0)
					(length 3.81)
					(name "155"
						(effects
							(font
								(size 1.27 1.27)
							)
						)
					)
					(number "155"
						(effects
							(font
								(size 1.27 1.27)
							)
						)
					)
				)
				(pin passive line
					(at 0 -33.02 0)
					(length 3.81)
					(name "157"
						(effects
							(font
								(size 1.27 1.27)
							)
						)
					)
					(number "157"
						(effects
							(font
								(size 1.27 1.27)
							)
						)
					)
				)
				(pin passive line
					(at 0 -35.56 0)
					(length 3.81)
					(name "159"
						(effects
							(font
								(size 1.27 1.27)
							)
						)
					)
					(number "159"
						(effects
							(font
								(size 1.27 1.27)
							)
						)
					)
				)
				(pin passive line
					(at 0 -38.1 0)
					(length 3.81)
					(name "161"
						(effects
							(font
								(size 1.27 1.27)
							)
						)
					)
					(number "161"
						(effects
							(font
								(size 1.27 1.27)
							)
						)
					)
				)
				(pin passive line
					(at 0 -40.64 0)
					(length 3.81)
					(name "163"
						(effects
							(font
								(size 1.27 1.27)
							)
						)
					)
					(number "163"
						(effects
							(font
								(size 1.27 1.27)
							)
						)
					)
				)
				(pin passive line
					(at 0 -43.18 0)
					(length 3.81)
					(name "165"
						(effects
							(font
								(size 1.27 1.27)
							)
						)
					)
					(number "165"
						(effects
							(font
								(size 1.27 1.27)
							)
						)
					)
				)
				(pin passive line
					(at 0 -45.72 0)
					(length 3.81)
					(name "167"
						(effects
							(font
								(size 1.27 1.27)
							)
						)
					)
					(number "167"
						(effects
							(font
								(size 1.27 1.27)
							)
						)
					)
				)
				(pin passive line
					(at 0 -48.26 0)
					(length 3.81)
					(name "169"
						(effects
							(font
								(size 1.27 1.27)
							)
						)
					)
					(number "169"
						(effects
							(font
								(size 1.27 1.27)
							)
						)
					)
				)
				(pin passive line
					(at 0 -50.8 0)
					(length 3.81)
					(name "171"
						(effects
							(font
								(size 1.27 1.27)
							)
						)
					)
					(number "171"
						(effects
							(font
								(size 1.27 1.27)
							)
						)
					)
				)
				(pin passive line
					(at 0 -53.34 0)
					(length 3.81)
					(name "173"
						(effects
							(font
								(size 1.27 1.27)
							)
						)
					)
					(number "173"
						(effects
							(font
								(size 1.27 1.27)
							)
						)
					)
				)
				(pin passive line
					(at 0 -55.88 0)
					(length 3.81)
					(name "175"
						(effects
							(font
								(size 1.27 1.27)
							)
						)
					)
					(number "175"
						(effects
							(font
								(size 1.27 1.27)
							)
						)
					)
				)
				(pin passive line
					(at 0 -58.42 0)
					(length 3.81)
					(name "177"
						(effects
							(font
								(size 1.27 1.27)
							)
						)
					)
					(number "177"
						(effects
							(font
								(size 1.27 1.27)
							)
						)
					)
				)
				(pin passive line
					(at 0 -60.96 0)
					(length 3.81)
					(name "179"
						(effects
							(font
								(size 1.27 1.27)
							)
						)
					)
					(number "179"
						(effects
							(font
								(size 1.27 1.27)
							)
						)
					)
				)
				(pin passive line
					(at 0 -63.5 0)
					(length 3.81)
					(name "181"
						(effects
							(font
								(size 1.27 1.27)
							)
						)
					)
					(number "181"
						(effects
							(font
								(size 1.27 1.27)
							)
						)
					)
				)
				(pin passive line
					(at 0 -66.04 0)
					(length 3.81)
					(name "183"
						(effects
							(font
								(size 1.27 1.27)
							)
						)
					)
					(number "183"
						(effects
							(font
								(size 1.27 1.27)
							)
						)
					)
				)
				(pin passive line
					(at 0 -68.58 0)
					(length 3.81)
					(name "185"
						(effects
							(font
								(size 1.27 1.27)
							)
						)
					)
					(number "185"
						(effects
							(font
								(size 1.27 1.27)
							)
						)
					)
				)
				(pin passive line
					(at 0 -71.12 0)
					(length 3.81)
					(name "187"
						(effects
							(font
								(size 1.27 1.27)
							)
						)
					)
					(number "187"
						(effects
							(font
								(size 1.27 1.27)
							)
						)
					)
				)
				(pin passive line
					(at 0 -73.66 0)
					(length 3.81)
					(name "189"
						(effects
							(font
								(size 1.27 1.27)
							)
						)
					)
					(number "189"
						(effects
							(font
								(size 1.27 1.27)
							)
						)
					)
				)
				(pin passive line
					(at 0 -76.2 0)
					(length 3.81)
					(name "191"
						(effects
							(font
								(size 1.27 1.27)
							)
						)
					)
					(number "191"
						(effects
							(font
								(size 1.27 1.27)
							)
						)
					)
				)
				(pin passive line
					(at 0 -78.74 0)
					(length 3.81)
					(name "193"
						(effects
							(font
								(size 1.27 1.27)
							)
						)
					)
					(number "193"
						(effects
							(font
								(size 1.27 1.27)
							)
						)
					)
				)
				(pin passive line
					(at 0 -81.28 0)
					(length 3.81)
					(name "195"
						(effects
							(font
								(size 1.27 1.27)
							)
						)
					)
					(number "195"
						(effects
							(font
								(size 1.27 1.27)
							)
						)
					)
				)
				(pin passive line
					(at 0 -83.82 0)
					(length 3.81)
					(name "197"
						(effects
							(font
								(size 1.27 1.27)
							)
						)
					)
					(number "197"
						(effects
							(font
								(size 1.27 1.27)
							)
						)
					)
				)
				(pin passive line
					(at 0 -86.36 0)
					(length 3.81)
					(name "199"
						(effects
							(font
								(size 1.27 1.27)
							)
						)
					)
					(number "199"
						(effects
							(font
								(size 1.27 1.27)
							)
						)
					)
				)
				(pin passive line
					(at 0 -88.9 0)
					(length 3.81)
					(name "201"
						(effects
							(font
								(size 1.27 1.27)
							)
						)
					)
					(number "201"
						(effects
							(font
								(size 1.27 1.27)
							)
						)
					)
				)
				(pin passive line
					(at 0 -91.44 0)
					(length 3.81)
					(name "203"
						(effects
							(font
								(size 1.27 1.27)
							)
						)
					)
					(number "203"
						(effects
							(font
								(size 1.27 1.27)
							)
						)
					)
				)
				(pin passive line
					(at 0 -93.98 0)
					(length 3.81)
					(name "205"
						(effects
							(font
								(size 1.27 1.27)
							)
						)
					)
					(number "205"
						(effects
							(font
								(size 1.27 1.27)
							)
						)
					)
				)
				(pin passive line
					(at 0 -96.52 0)
					(length 3.81)
					(name "207"
						(effects
							(font
								(size 1.27 1.27)
							)
						)
					)
					(number "207"
						(effects
							(font
								(size 1.27 1.27)
							)
						)
					)
				)
				(pin passive line
					(at 0 -99.06 0)
					(length 3.81)
					(name "209"
						(effects
							(font
								(size 1.27 1.27)
							)
						)
					)
					(number "209"
						(effects
							(font
								(size 1.27 1.27)
							)
						)
					)
				)
				(pin passive line
					(at 0 -101.6 0)
					(length 3.81)
					(name "211"
						(effects
							(font
								(size 1.27 1.27)
							)
						)
					)
					(number "211"
						(effects
							(font
								(size 1.27 1.27)
							)
						)
					)
				)
				(pin passive line
					(at 0 -104.14 0)
					(length 3.81)
					(name "213"
						(effects
							(font
								(size 1.27 1.27)
							)
						)
					)
					(number "213"
						(effects
							(font
								(size 1.27 1.27)
							)
						)
					)
				)
				(pin passive line
					(at 0 -106.68 0)
					(length 3.81)
					(name "215"
						(effects
							(font
								(size 1.27 1.27)
							)
						)
					)
					(number "215"
						(effects
							(font
								(size 1.27 1.27)
							)
						)
					)
				)
				(pin passive line
					(at 0 -109.22 0)
					(length 3.81)
					(name "217"
						(effects
							(font
								(size 1.27 1.27)
							)
						)
					)
					(number "217"
						(effects
							(font
								(size 1.27 1.27)
							)
						)
					)
				)
				(pin passive line
					(at 0 -111.76 0)
					(length 3.81)
					(name "219"
						(effects
							(font
								(size 1.27 1.27)
							)
						)
					)
					(number "219"
						(effects
							(font
								(size 1.27 1.27)
							)
						)
					)
				)
				(pin passive line
					(at 0 -114.3 0)
					(length 3.81)
					(name "221"
						(effects
							(font
								(size 1.27 1.27)
							)
						)
					)
					(number "221"
						(effects
							(font
								(size 1.27 1.27)
							)
						)
					)
				)
				(pin passive line
					(at 0 -116.84 0)
					(length 3.81)
					(name "223"
						(effects
							(font
								(size 1.27 1.27)
							)
						)
					)
					(number "223"
						(effects
							(font
								(size 1.27 1.27)
							)
						)
					)
				)
				(pin passive line
					(at 0 -119.38 0)
					(length 3.81)
					(name "225"
						(effects
							(font
								(size 1.27 1.27)
							)
						)
					)
					(number "225"
						(effects
							(font
								(size 1.27 1.27)
							)
						)
					)
				)
				(pin passive line
					(at 0 -121.92 0)
					(length 3.81)
					(name "227"
						(effects
							(font
								(size 1.27 1.27)
							)
						)
					)
					(number "227"
						(effects
							(font
								(size 1.27 1.27)
							)
						)
					)
				)
				(pin passive line
					(at 0 -124.46 0)
					(length 3.81)
					(name "229"
						(effects
							(font
								(size 1.27 1.27)
							)
						)
					)
					(number "229"
						(effects
							(font
								(size 1.27 1.27)
							)
						)
					)
				)
				(pin passive line
					(at 0 -127 0)
					(length 3.81)
					(name "231"
						(effects
							(font
								(size 1.27 1.27)
							)
						)
					)
					(number "231"
						(effects
							(font
								(size 1.27 1.27)
							)
						)
					)
				)
				(pin passive line
					(at 0 -129.54 0)
					(length 3.81)
					(name "233"
						(effects
							(font
								(size 1.27 1.27)
							)
						)
					)
					(number "233"
						(effects
							(font
								(size 1.27 1.27)
							)
						)
					)
				)
				(pin passive line
					(at 0 -132.08 0)
					(length 3.81)
					(name "235"
						(effects
							(font
								(size 1.27 1.27)
							)
						)
					)
					(number "235"
						(effects
							(font
								(size 1.27 1.27)
							)
						)
					)
				)
				(pin passive line
					(at 0 -134.62 0)
					(length 3.81)
					(name "237"
						(effects
							(font
								(size 1.27 1.27)
							)
						)
					)
					(number "237"
						(effects
							(font
								(size 1.27 1.27)
							)
						)
					)
				)
				(pin passive line
					(at 0 -137.16 0)
					(length 3.81)
					(name "239"
						(effects
							(font
								(size 1.27 1.27)
							)
						)
					)
					(number "239"
						(effects
							(font
								(size 1.27 1.27)
							)
						)
					)
				)
				(pin passive line
					(at 0 -139.7 0)
					(length 3.81)
					(name "241"
						(effects
							(font
								(size 1.27 1.27)
							)
						)
					)
					(number "241"
						(effects
							(font
								(size 1.27 1.27)
							)
						)
					)
				)
				(pin passive line
					(at 0 -142.24 0)
					(length 3.81)
					(name "243"
						(effects
							(font
								(size 1.27 1.27)
							)
						)
					)
					(number "243"
						(effects
							(font
								(size 1.27 1.27)
							)
						)
					)
				)
				(pin passive line
					(at 0 -144.78 0)
					(length 3.81)
					(name "245"
						(effects
							(font
								(size 1.27 1.27)
							)
						)
					)
					(number "245"
						(effects
							(font
								(size 1.27 1.27)
							)
						)
					)
				)
				(pin passive line
					(at 0 -147.32 0)
					(length 3.81)
					(name "247"
						(effects
							(font
								(size 1.27 1.27)
							)
						)
					)
					(number "247"
						(effects
							(font
								(size 1.27 1.27)
							)
						)
					)
				)
				(pin passive line
					(at 0 -149.86 0)
					(length 3.81)
					(name "249"
						(effects
							(font
								(size 1.27 1.27)
							)
						)
					)
					(number "249"
						(effects
							(font
								(size 1.27 1.27)
							)
						)
					)
				)
				(pin passive line
					(at 0 -152.4 0)
					(length 3.81)
					(name "251"
						(effects
							(font
								(size 1.27 1.27)
							)
						)
					)
					(number "251"
						(effects
							(font
								(size 1.27 1.27)
							)
						)
					)
				)
				(pin passive line
					(at 0 -154.94 0)
					(length 3.81)
					(name "253"
						(effects
							(font
								(size 1.27 1.27)
							)
						)
					)
					(number "253"
						(effects
							(font
								(size 1.27 1.27)
							)
						)
					)
				)
				(pin passive line
					(at 0 -157.48 0)
					(length 3.81)
					(name "255"
						(effects
							(font
								(size 1.27 1.27)
							)
						)
					)
					(number "255"
						(effects
							(font
								(size 1.27 1.27)
							)
						)
					)
				)
				(pin passive line
					(at 0 -160.02 0)
					(length 3.81)
					(name "257"
						(effects
							(font
								(size 1.27 1.27)
							)
						)
					)
					(number "257"
						(effects
							(font
								(size 1.27 1.27)
							)
						)
					)
				)
				(pin passive line
					(at 0 -162.56 0)
					(length 3.81)
					(name "259"
						(effects
							(font
								(size 1.27 1.27)
							)
						)
					)
					(number "259"
						(effects
							(font
								(size 1.27 1.27)
							)
						)
					)
				)
				(pin passive line
					(at 22.86 0 180)
					(length 3.81)
					(name "132"
						(effects
							(font
								(size 1.27 1.27)
							)
						)
					)
					(number "132"
						(effects
							(font
								(size 1.27 1.27)
							)
						)
					)
				)
				(pin passive line
					(at 22.86 -2.54 180)
					(length 3.81)
					(name "134"
						(effects
							(font
								(size 1.27 1.27)
							)
						)
					)
					(number "134"
						(effects
							(font
								(size 1.27 1.27)
							)
						)
					)
				)
				(pin passive line
					(at 22.86 -5.08 180)
					(length 3.81)
					(name "136"
						(effects
							(font
								(size 1.27 1.27)
							)
						)
					)
					(number "136"
						(effects
							(font
								(size 1.27 1.27)
							)
						)
					)
				)
				(pin passive line
					(at 22.86 -7.62 180)
					(length 3.81)
					(name "138"
						(effects
							(font
								(size 1.27 1.27)
							)
						)
					)
					(number "138"
						(effects
							(font
								(size 1.27 1.27)
							)
						)
					)
				)
				(pin passive line
					(at 22.86 -10.16 180)
					(length 3.81)
					(name "140"
						(effects
							(font
								(size 1.27 1.27)
							)
						)
					)
					(number "140"
						(effects
							(font
								(size 1.27 1.27)
							)
						)
					)
				)
				(pin passive line
					(at 22.86 -12.7 180)
					(length 3.81)
					(name "142"
						(effects
							(font
								(size 1.27 1.27)
							)
						)
					)
					(number "142"
						(effects
							(font
								(size 1.27 1.27)
							)
						)
					)
				)
				(pin passive line
					(at 22.86 -15.24 180)
					(length 3.81)
					(name "144"
						(effects
							(font
								(size 1.27 1.27)
							)
						)
					)
					(number "144"
						(effects
							(font
								(size 1.27 1.27)
							)
						)
					)
				)
				(pin passive line
					(at 22.86 -17.78 180)
					(length 3.81)
					(name "146"
						(effects
							(font
								(size 1.27 1.27)
							)
						)
					)
					(number "146"
						(effects
							(font
								(size 1.27 1.27)
							)
						)
					)
				)
				(pin passive line
					(at 22.86 -20.32 180)
					(length 3.81)
					(name "148"
						(effects
							(font
								(size 1.27 1.27)
							)
						)
					)
					(number "148"
						(effects
							(font
								(size 1.27 1.27)
							)
						)
					)
				)
				(pin passive line
					(at 22.86 -22.86 180)
					(length 3.81)
					(name "150"
						(effects
							(font
								(size 1.27 1.27)
							)
						)
					)
					(number "150"
						(effects
							(font
								(size 1.27 1.27)
							)
						)
					)
				)
				(pin passive line
					(at 22.86 -25.4 180)
					(length 3.81)
					(name "152"
						(effects
							(font
								(size 1.27 1.27)
							)
						)
					)
					(number "152"
						(effects
							(font
								(size 1.27 1.27)
							)
						)
					)
				)
				(pin passive line
					(at 22.86 -27.94 180)
					(length 3.81)
					(name "154"
						(effects
							(font
								(size 1.27 1.27)
							)
						)
					)
					(number "154"
						(effects
							(font
								(size 1.27 1.27)
							)
						)
					)
				)
				(pin passive line
					(at 22.86 -30.48 180)
					(length 3.81)
					(name "156"
						(effects
							(font
								(size 1.27 1.27)
							)
						)
					)
					(number "156"
						(effects
							(font
								(size 1.27 1.27)
							)
						)
					)
				)
				(pin passive line
					(at 22.86 -33.02 180)
					(length 3.81)
					(name "158"
						(effects
							(font
								(size 1.27 1.27)
							)
						)
					)
					(number "158"
						(effects
							(font
								(size 1.27 1.27)
							)
						)
					)
				)
				(pin passive line
					(at 22.86 -35.56 180)
					(length 3.81)
					(name "160"
						(effects
							(font
								(size 1.27 1.27)
							)
						)
					)
					(number "160"
						(effects
							(font
								(size 1.27 1.27)
							)
						)
					)
				)
				(pin passive line
					(at 22.86 -38.1 180)
					(length 3.81)
					(name "162"
						(effects
							(font
								(size 1.27 1.27)
							)
						)
					)
					(number "162"
						(effects
							(font
								(size 1.27 1.27)
							)
						)
					)
				)
				(pin passive line
					(at 22.86 -40.64 180)
					(length 3.81)
					(name "164"
						(effects
							(font
								(size 1.27 1.27)
							)
						)
					)
					(number "164"
						(effects
							(font
								(size 1.27 1.27)
							)
						)
					)
				)
				(pin passive line
					(at 22.86 -43.18 180)
					(length 3.81)
					(name "166"
						(effects
							(font
								(size 1.27 1.27)
							)
						)
					)
					(number "166"
						(effects
							(font
								(size 1.27 1.27)
							)
						)
					)
				)
				(pin passive line
					(at 22.86 -45.72 180)
					(length 3.81)
					(name "168"
						(effects
							(font
								(size 1.27 1.27)
							)
						)
					)
					(number "168"
						(effects
							(font
								(size 1.27 1.27)
							)
						)
					)
				)
				(pin passive line
					(at 22.86 -48.26 180)
					(length 3.81)
					(name "170"
						(effects
							(font
								(size 1.27 1.27)
							)
						)
					)
					(number "170"
						(effects
							(font
								(size 1.27 1.27)
							)
						)
					)
				)
				(pin passive line
					(at 22.86 -50.8 180)
					(length 3.81)
					(name "172"
						(effects
							(font
								(size 1.27 1.27)
							)
						)
					)
					(number "172"
						(effects
							(font
								(size 1.27 1.27)
							)
						)
					)
				)
				(pin passive line
					(at 22.86 -53.34 180)
					(length 3.81)
					(name "174"
						(effects
							(font
								(size 1.27 1.27)
							)
						)
					)
					(number "174"
						(effects
							(font
								(size 1.27 1.27)
							)
						)
					)
				)
				(pin passive line
					(at 22.86 -55.88 180)
					(length 3.81)
					(name "176"
						(effects
							(font
								(size 1.27 1.27)
							)
						)
					)
					(number "176"
						(effects
							(font
								(size 1.27 1.27)
							)
						)
					)
				)
				(pin passive line
					(at 22.86 -58.42 180)
					(length 3.81)
					(name "178"
						(effects
							(font
								(size 1.27 1.27)
							)
						)
					)
					(number "178"
						(effects
							(font
								(size 1.27 1.27)
							)
						)
					)
				)
				(pin passive line
					(at 22.86 -60.96 180)
					(length 3.81)
					(name "180"
						(effects
							(font
								(size 1.27 1.27)
							)
						)
					)
					(number "180"
						(effects
							(font
								(size 1.27 1.27)
							)
						)
					)
				)
				(pin passive line
					(at 22.86 -63.5 180)
					(length 3.81)
					(name "182"
						(effects
							(font
								(size 1.27 1.27)
							)
						)
					)
					(number "182"
						(effects
							(font
								(size 1.27 1.27)
							)
						)
					)
				)
				(pin passive line
					(at 22.86 -66.04 180)
					(length 3.81)
					(name "184"
						(effects
							(font
								(size 1.27 1.27)
							)
						)
					)
					(number "184"
						(effects
							(font
								(size 1.27 1.27)
							)
						)
					)
				)
				(pin passive line
					(at 22.86 -68.58 180)
					(length 3.81)
					(name "186"
						(effects
							(font
								(size 1.27 1.27)
							)
						)
					)
					(number "186"
						(effects
							(font
								(size 1.27 1.27)
							)
						)
					)
				)
				(pin passive line
					(at 22.86 -71.12 180)
					(length 3.81)
					(name "188"
						(effects
							(font
								(size 1.27 1.27)
							)
						)
					)
					(number "188"
						(effects
							(font
								(size 1.27 1.27)
							)
						)
					)
				)
				(pin passive line
					(at 22.86 -73.66 180)
					(length 3.81)
					(name "190"
						(effects
							(font
								(size 1.27 1.27)
							)
						)
					)
					(number "190"
						(effects
							(font
								(size 1.27 1.27)
							)
						)
					)
				)
				(pin passive line
					(at 22.86 -76.2 180)
					(length 3.81)
					(name "192"
						(effects
							(font
								(size 1.27 1.27)
							)
						)
					)
					(number "192"
						(effects
							(font
								(size 1.27 1.27)
							)
						)
					)
				)
				(pin passive line
					(at 22.86 -78.74 180)
					(length 3.81)
					(name "194"
						(effects
							(font
								(size 1.27 1.27)
							)
						)
					)
					(number "194"
						(effects
							(font
								(size 1.27 1.27)
							)
						)
					)
				)
				(pin passive line
					(at 22.86 -81.28 180)
					(length 3.81)
					(name "196"
						(effects
							(font
								(size 1.27 1.27)
							)
						)
					)
					(number "196"
						(effects
							(font
								(size 1.27 1.27)
							)
						)
					)
				)
				(pin passive line
					(at 22.86 -83.82 180)
					(length 3.81)
					(name "198"
						(effects
							(font
								(size 1.27 1.27)
							)
						)
					)
					(number "198"
						(effects
							(font
								(size 1.27 1.27)
							)
						)
					)
				)
				(pin passive line
					(at 22.86 -86.36 180)
					(length 3.81)
					(name "200"
						(effects
							(font
								(size 1.27 1.27)
							)
						)
					)
					(number "200"
						(effects
							(font
								(size 1.27 1.27)
							)
						)
					)
				)
				(pin passive line
					(at 22.86 -88.9 180)
					(length 3.81)
					(name "202"
						(effects
							(font
								(size 1.27 1.27)
							)
						)
					)
					(number "202"
						(effects
							(font
								(size 1.27 1.27)
							)
						)
					)
				)
				(pin passive line
					(at 22.86 -91.44 180)
					(length 3.81)
					(name "204"
						(effects
							(font
								(size 1.27 1.27)
							)
						)
					)
					(number "204"
						(effects
							(font
								(size 1.27 1.27)
							)
						)
					)
				)
				(pin passive line
					(at 22.86 -93.98 180)
					(length 3.81)
					(name "206"
						(effects
							(font
								(size 1.27 1.27)
							)
						)
					)
					(number "206"
						(effects
							(font
								(size 1.27 1.27)
							)
						)
					)
				)
				(pin passive line
					(at 22.86 -96.52 180)
					(length 3.81)
					(name "208"
						(effects
							(font
								(size 1.27 1.27)
							)
						)
					)
					(number "208"
						(effects
							(font
								(size 1.27 1.27)
							)
						)
					)
				)
				(pin passive line
					(at 22.86 -99.06 180)
					(length 3.81)
					(name "210"
						(effects
							(font
								(size 1.27 1.27)
							)
						)
					)
					(number "210"
						(effects
							(font
								(size 1.27 1.27)
							)
						)
					)
				)
				(pin passive line
					(at 22.86 -101.6 180)
					(length 3.81)
					(name "212"
						(effects
							(font
								(size 1.27 1.27)
							)
						)
					)
					(number "212"
						(effects
							(font
								(size 1.27 1.27)
							)
						)
					)
				)
				(pin passive line
					(at 22.86 -104.14 180)
					(length 3.81)
					(name "214"
						(effects
							(font
								(size 1.27 1.27)
							)
						)
					)
					(number "214"
						(effects
							(font
								(size 1.27 1.27)
							)
						)
					)
				)
				(pin passive line
					(at 22.86 -106.68 180)
					(length 3.81)
					(name "216"
						(effects
							(font
								(size 1.27 1.27)
							)
						)
					)
					(number "216"
						(effects
							(font
								(size 1.27 1.27)
							)
						)
					)
				)
				(pin passive line
					(at 22.86 -109.22 180)
					(length 3.81)
					(name "218"
						(effects
							(font
								(size 1.27 1.27)
							)
						)
					)
					(number "218"
						(effects
							(font
								(size 1.27 1.27)
							)
						)
					)
				)
				(pin passive line
					(at 22.86 -111.76 180)
					(length 3.81)
					(name "220"
						(effects
							(font
								(size 1.27 1.27)
							)
						)
					)
					(number "220"
						(effects
							(font
								(size 1.27 1.27)
							)
						)
					)
				)
				(pin passive line
					(at 22.86 -114.3 180)
					(length 3.81)
					(name "222"
						(effects
							(font
								(size 1.27 1.27)
							)
						)
					)
					(number "222"
						(effects
							(font
								(size 1.27 1.27)
							)
						)
					)
				)
				(pin passive line
					(at 22.86 -116.84 180)
					(length 3.81)
					(name "224"
						(effects
							(font
								(size 1.27 1.27)
							)
						)
					)
					(number "224"
						(effects
							(font
								(size 1.27 1.27)
							)
						)
					)
				)
				(pin passive line
					(at 22.86 -119.38 180)
					(length 3.81)
					(name "226"
						(effects
							(font
								(size 1.27 1.27)
							)
						)
					)
					(number "226"
						(effects
							(font
								(size 1.27 1.27)
							)
						)
					)
				)
				(pin passive line
					(at 22.86 -121.92 180)
					(length 3.81)
					(name "228"
						(effects
							(font
								(size 1.27 1.27)
							)
						)
					)
					(number "228"
						(effects
							(font
								(size 1.27 1.27)
							)
						)
					)
				)
				(pin passive line
					(at 22.86 -124.46 180)
					(length 3.81)
					(name "230"
						(effects
							(font
								(size 1.27 1.27)
							)
						)
					)
					(number "230"
						(effects
							(font
								(size 1.27 1.27)
							)
						)
					)
				)
				(pin passive line
					(at 22.86 -127 180)
					(length 3.81)
					(name "232"
						(effects
							(font
								(size 1.27 1.27)
							)
						)
					)
					(number "232"
						(effects
							(font
								(size 1.27 1.27)
							)
						)
					)
				)
				(pin passive line
					(at 22.86 -129.54 180)
					(length 3.81)
					(name "234"
						(effects
							(font
								(size 1.27 1.27)
							)
						)
					)
					(number "234"
						(effects
							(font
								(size 1.27 1.27)
							)
						)
					)
				)
				(pin passive line
					(at 22.86 -132.08 180)
					(length 3.81)
					(name "236"
						(effects
							(font
								(size 1.27 1.27)
							)
						)
					)
					(number "236"
						(effects
							(font
								(size 1.27 1.27)
							)
						)
					)
				)
				(pin passive line
					(at 22.86 -134.62 180)
					(length 3.81)
					(name "238"
						(effects
							(font
								(size 1.27 1.27)
							)
						)
					)
					(number "238"
						(effects
							(font
								(size 1.27 1.27)
							)
						)
					)
				)
				(pin passive line
					(at 22.86 -137.16 180)
					(length 3.81)
					(name "240"
						(effects
							(font
								(size 1.27 1.27)
							)
						)
					)
					(number "240"
						(effects
							(font
								(size 1.27 1.27)
							)
						)
					)
				)
				(pin passive line
					(at 22.86 -139.7 180)
					(length 3.81)
					(name "242"
						(effects
							(font
								(size 1.27 1.27)
							)
						)
					)
					(number "242"
						(effects
							(font
								(size 1.27 1.27)
							)
						)
					)
				)
				(pin passive line
					(at 22.86 -142.24 180)
					(length 3.81)
					(name "244"
						(effects
							(font
								(size 1.27 1.27)
							)
						)
					)
					(number "244"
						(effects
							(font
								(size 1.27 1.27)
							)
						)
					)
				)
				(pin passive line
					(at 22.86 -144.78 180)
					(length 3.81)
					(name "246"
						(effects
							(font
								(size 1.27 1.27)
							)
						)
					)
					(number "246"
						(effects
							(font
								(size 1.27 1.27)
							)
						)
					)
				)
				(pin passive line
					(at 22.86 -147.32 180)
					(length 3.81)
					(name "248"
						(effects
							(font
								(size 1.27 1.27)
							)
						)
					)
					(number "248"
						(effects
							(font
								(size 1.27 1.27)
							)
						)
					)
				)
				(pin passive line
					(at 22.86 -149.86 180)
					(length 3.81)
					(name "250"
						(effects
							(font
								(size 1.27 1.27)
							)
						)
					)
					(number "250"
						(effects
							(font
								(size 1.27 1.27)
							)
						)
					)
				)
				(pin passive line
					(at 22.86 -152.4 180)
					(length 3.81)
					(name "252"
						(effects
							(font
								(size 1.27 1.27)
							)
						)
					)
					(number "252"
						(effects
							(font
								(size 1.27 1.27)
							)
						)
					)
				)
				(pin passive line
					(at 22.86 -154.94 180)
					(length 3.81)
					(name "254"
						(effects
							(font
								(size 1.27 1.27)
							)
						)
					)
					(number "254"
						(effects
							(font
								(size 1.27 1.27)
							)
						)
					)
				)
				(pin passive line
					(at 22.86 -157.48 180)
					(length 3.81)
					(name "256"
						(effects
							(font
								(size 1.27 1.27)
							)
						)
					)
					(number "256"
						(effects
							(font
								(size 1.27 1.27)
							)
						)
					)
				)
				(pin passive line
					(at 22.86 -160.02 180)
					(length 3.81)
					(name "258"
						(effects
							(font
								(size 1.27 1.27)
							)
						)
					)
					(number "258"
						(effects
							(font
								(size 1.27 1.27)
							)
						)
					)
				)
				(pin passive line
					(at 22.86 -162.56 180)
					(length 3.81)
					(name "260"
						(effects
							(font
								(size 1.27 1.27)
							)
						)
					)
					(number "260"
						(effects
							(font
								(size 1.27 1.27)
							)
						)
					)
				)
			)
		)
	(symbol "antmicroFerriteBeadsandChips:FB_220Z_1.5A_WE-CBF_0805"
			(pin_numbers
				(hide yes)
			)
			(pin_names
				(hide yes)
			)
			(exclude_from_sim no)
			(in_bom yes)
			(on_board yes)
			(property "Reference" "FB"
				(at 15.24 0 0)
				(effects
					(font
						(size 1.27 1.27)
						(thickness 0.15)
					)
					(justify left bottom)
				)
			)
			(property "Value" "FB_220Z_1.5A_WE-CBF_0805"
				(at 15.24 -2.54 0)
				(effects
					(font
						(size 1.27 1.27)
						(thickness 0.15)
					)
					(justify left bottom)
					(hide yes)
				)
			)
			(property "Footprint" "antmicro-footprints:FB_0805_2012Metric"
				(at 15.24 -7.62 0)
				(effects
					(font
						(size 1.27 1.27)
						(thickness 0.15)
					)
					(justify left bottom)
					(hide yes)
				)
			)
			(property "Datasheet" "https://www.we-online.com/katalog/datasheet/742792022.pdf"
				(at 15.24 -10.16 0)
				(effects
					(font
						(size 1.27 1.27)
						(thickness 0.15)
					)
					(justify left bottom)
					(hide yes)
				)
			)
			(property "Description" "Ferrite Bead, 0805 [2012 Metric], 220 ohm, 2 A, WE-CBF, 0.05 ohm, ± 25%, High Current"
				(at 0 0 0)
				(effects
					(font
						(size 1.27 1.27)
					)
					(hide yes)
				)
			)
			(property "Val" "220Z/1.5A"
				(at 15.24 -5.08 0)
				(effects
					(font
						(size 1.27 1.27)
						(thickness 0.15)
					)
					(justify left bottom)
				)
			)
			(property "MPN" "742792022"
				(at 15.24 -12.7 0)
				(effects
					(font
						(size 1.27 1.27)
						(thickness 0.15)
					)
					(justify left bottom)
					(hide yes)
				)
			)
			(property "Manufacturer" "Würth Elektronik"
				(at 15.24 -15.24 0)
				(effects
					(font
						(size 1.27 1.27)
						(thickness 0.15)
					)
					(justify left bottom)
					(hide yes)
				)
			)
			(property "Current" ""
				(at 20.32 -22.86 0)
				(effects
					(font
						(size 1.27 1.27)
						(thickness 0.15)
					)
					(justify left bottom)
					(hide yes)
				)
			)
			(property "Author" "Antmicro"
				(at 15.24 -17.78 0)
				(effects
					(font
						(size 1.27 1.27)
						(thickness 0.15)
					)
					(justify left bottom)
					(hide yes)
				)
			)
			(property "License" "Apache-2.0"
				(at 15.24 -20.32 0)
				(effects
					(font
						(size 1.27 1.27)
						(thickness 0.15)
					)
					(justify left bottom)
					(hide yes)
				)
			)
			(property "Public" "False"
				(at 20.32 -15.24 0)
				(effects
					(font
						(size 1.27 1.27)
					)
					(justify left bottom)
					(hide yes)
				)
			)
			(property "ki_keywords" "0805, SMT, FERRITE BEAD, PASSIVE"
				(at 0 0 0)
				(effects
					(font
						(size 1.27 1.27)
					)
					(hide yes)
				)
			)
			(symbol "FB_220Z_1.5A_WE-CBF_0805_0_1"
				(polyline
					(pts
						(xy 1.651 0) (xy 1.2446 0)
					)
					(stroke
						(width 0)
						(type default)
					)
					(fill
						(type none)
					)
				)
				(polyline
					(pts
						(xy 2.2606 -1.8288) (xy 1.0414 -1.1176) (xy 2.7432 1.8288) (xy 3.9624 1.1176) (xy 2.2606 -1.8288)
					)
					(stroke
						(width 0)
						(type default)
					)
					(fill
						(type none)
					)
				)
				(polyline
					(pts
						(xy 3.81 0) (xy 3.3274 0)
					)
					(stroke
						(width 0)
						(type default)
					)
					(fill
						(type none)
					)
				)
			)
			(symbol "FB_220Z_1.5A_WE-CBF_0805_1_1"
				(pin passive line
					(at 0 0 0)
					(length 1.27)
					(name "~"
						(effects
							(font
								(size 1.27 1.27)
							)
						)
					)
					(number "1"
						(effects
							(font
								(size 1.27 1.27)
							)
						)
					)
				)
				(pin passive line
					(at 5.08 0 180)
					(length 1.27)
					(name "~"
						(effects
							(font
								(size 1.27 1.27)
							)
						)
					)
					(number "2"
						(effects
							(font
								(size 1.27 1.27)
							)
						)
					)
				)
			)
		)
	(symbol "antmicroFixedInductors:L_2u2_1.5A_0806"
			(pin_numbers
				(hide yes)
			)
			(pin_names
				(hide yes)
			)
			(exclude_from_sim no)
			(in_bom yes)
			(on_board yes)
			(property "Reference" "L"
				(at 13.97 0 0)
				(effects
					(font
						(size 1.27 1.27)
						(thickness 0.15)
					)
					(justify left bottom)
				)
			)
			(property "Value" "L_2.2u_1.5A_0806"
				(at 13.97 -2.54 0)
				(effects
					(font
						(size 1.27 1.27)
						(thickness 0.15)
					)
					(justify left bottom)
					(hide yes)
				)
			)
			(property "Footprint" "antmicro-footprints:L_0806_2016Metric"
				(at 13.97 -7.62 0)
				(effects
					(font
						(size 1.27 1.27)
						(thickness 0.15)
					)
					(justify left bottom)
					(hide yes)
				)
			)
			(property "Datasheet" "https://search.murata.co.jp/Ceramy/image/img/P02/J(E)TE243A-0011.pdf"
				(at 13.97 -10.16 0)
				(effects
					(font
						(size 1.27 1.27)
						(thickness 0.15)
					)
					(justify left bottom)
					(hide yes)
				)
			)
			(property "Description" ""
				(at 0 0 0)
				(effects
					(font
						(size 1.27 1.27)
					)
					(hide yes)
				)
			)
			(property "Val" "2.2uH/1.5A"
				(at 13.97 -5.08 0)
				(effects
					(font
						(size 1.27 1.27)
						(thickness 0.15)
					)
					(justify left bottom)
				)
			)
			(property "Manufacturer" "Murata"
				(at 13.97 -12.7 0)
				(effects
					(font
						(size 1.27 1.27)
						(thickness 0.15)
					)
					(justify left bottom)
					(hide yes)
				)
			)
			(property "MPN" "1285AS-H-2R2M=P2"
				(at 13.97 -15.24 0)
				(effects
					(font
						(size 1.27 1.27)
						(thickness 0.15)
					)
					(justify left bottom)
					(hide yes)
				)
			)
			(property "ISat" ""
				(at 13.97 -16.51 0)
				(effects
					(font
						(size 1.27 1.27)
					)
					(justify left)
					(hide yes)
				)
			)
			(property "IMax" ""
				(at 13.97 -20.32 0)
				(effects
					(font
						(size 1.27 1.27)
						(thickness 0.15)
					)
					(justify left bottom)
					(hide yes)
				)
			)
			(property "Size" "2.0x1.6"
				(at 13.97 -22.86 0)
				(effects
					(font
						(size 1.27 1.27)
						(thickness 0.15)
					)
					(justify left bottom)
					(hide yes)
				)
			)
			(property "Author" "Antmicro"
				(at 13.97 -25.4 0)
				(effects
					(font
						(size 1.27 1.27)
						(thickness 0.15)
					)
					(justify left bottom)
					(hide yes)
				)
			)
			(property "License" "Apache-2.0"
				(at 13.97 -27.94 0)
				(effects
					(font
						(size 1.27 1.27)
						(thickness 0.15)
					)
					(justify left bottom)
					(hide yes)
				)
			)
			(symbol "L_2u2_1.5A_0806_0_1"
				(arc
					(start 0.508 0)
					(mid 1.016 0.5058)
					(end 1.524 0)
					(stroke
						(width 0)
						(type default)
					)
					(fill
						(type none)
					)
				)
				(arc
					(start 1.524 0)
					(mid 2.032 0.5058)
					(end 2.54 0)
					(stroke
						(width 0)
						(type default)
					)
					(fill
						(type none)
					)
				)
				(arc
					(start 2.54 0)
					(mid 3.048 0.5058)
					(end 3.556 0)
					(stroke
						(width 0)
						(type default)
					)
					(fill
						(type none)
					)
				)
				(arc
					(start 3.556 0)
					(mid 4.064 0.5058)
					(end 4.572 0)
					(stroke
						(width 0)
						(type default)
					)
					(fill
						(type none)
					)
				)
			)
			(symbol "L_2u2_1.5A_0806_1_1"
				(pin passive line
					(at 0 0 0)
					(length 0.508)
					(name "~"
						(effects
							(font
								(size 1.27 1.27)
							)
						)
					)
					(number "1"
						(effects
							(font
								(size 1.27 1.27)
							)
						)
					)
				)
				(pin passive line
					(at 5.08 0 180)
					(length 0.508)
					(name "~"
						(effects
							(font
								(size 1.27 1.27)
							)
						)
					)
					(number "2"
						(effects
							(font
								(size 1.27 1.27)
							)
						)
					)
				)
			)
		)
	(symbol "antmicroInterfaceIOExpanders:PCA6408A_TSSOP"
			(exclude_from_sim no)
			(in_bom yes)
			(on_board yes)
			(property "Reference" "U"
				(at 35.56 -2.54 0)
				(effects
					(font
						(size 1.27 1.27)
						(thickness 0.15)
					)
					(justify left bottom)
				)
			)
			(property "Value" "PCA6408A_TSSOP"
				(at 35.56 -7.62 0)
				(effects
					(font
						(size 1.27 1.27)
						(thickness 0.15)
					)
					(justify left bottom)
					(hide yes)
				)
			)
			(property "Footprint" "antmicro-footprints:TSSOP-16_4.4x5mm_P0.65mm"
				(at 35.56 -10.16 0)
				(effects
					(font
						(size 1.27 1.27)
						(thickness 0.15)
					)
					(justify left bottom)
					(hide yes)
				)
			)
			(property "Datasheet" "https://www.mouser.com/datasheet/2/302/PCA6408A-1127604.pdf"
				(at 35.56 -12.7 0)
				(effects
					(font
						(size 1.27 1.27)
						(thickness 0.15)
					)
					(justify left bottom)
					(hide yes)
				)
			)
			(property "Description" "I/O Expander, 8 bit, I2C, SMBus, 1.65-5.5 V, TSSOP, 16 Pins"
				(at 0 0 0)
				(effects
					(font
						(size 1.27 1.27)
					)
					(hide yes)
				)
			)
			(property "Manufacturer" "NXP"
				(at 35.56 -15.24 0)
				(effects
					(font
						(size 1.27 1.27)
						(thickness 0.15)
					)
					(justify left bottom)
					(hide yes)
				)
			)
			(property "MPN" "PCA6408APW"
				(at 35.56 -5.08 0)
				(effects
					(font
						(size 1.27 1.27)
						(thickness 0.15)
					)
					(justify left bottom)
				)
			)
			(property "Author" "Antmicro"
				(at 35.56 -17.78 0)
				(effects
					(font
						(size 1.27 1.27)
						(thickness 0.15)
					)
					(justify left bottom)
					(hide yes)
				)
			)
			(property "License" "Apache-2.0"
				(at 35.56 -20.32 0)
				(effects
					(font
						(size 1.27 1.27)
						(thickness 0.15)
					)
					(justify left bottom)
					(hide yes)
				)
			)
			(property "ki_keywords" "SMT, INTERFACE, IC, I2C"
				(at 0 0 0)
				(effects
					(font
						(size 1.27 1.27)
					)
					(hide yes)
				)
			)
			(symbol "PCA6408A_TSSOP_1_1"
				(rectangle
					(start 2.54 2.54)
					(end 20.32 -27.94)
					(stroke
						(width 0.254)
						(type default)
					)
					(fill
						(type background)
					)
				)
				(pin power_in line
					(at 0 0 0)
					(length 2.54)
					(name "VDD(P)"
						(effects
							(font
								(size 1.27 1.27)
							)
						)
					)
					(number "16"
						(effects
							(font
								(size 1.27 1.27)
							)
						)
					)
				)
				(pin power_in line
					(at 0 -2.54 0)
					(length 2.54)
					(name "VDD(I2C)"
						(effects
							(font
								(size 1.27 1.27)
							)
						)
					)
					(number "1"
						(effects
							(font
								(size 1.27 1.27)
							)
						)
					)
				)
				(pin bidirectional line
					(at 0 -7.62 0)
					(length 2.54)
					(name "SDA"
						(effects
							(font
								(size 1.27 1.27)
							)
						)
					)
					(number "15"
						(effects
							(font
								(size 1.27 1.27)
							)
						)
					)
				)
				(pin input line
					(at 0 -10.16 0)
					(length 2.54)
					(name "SCL"
						(effects
							(font
								(size 1.27 1.27)
							)
						)
					)
					(number "14"
						(effects
							(font
								(size 1.27 1.27)
							)
						)
					)
				)
				(pin output line
					(at 0 -15.24 0)
					(length 2.54)
					(name "~{INT}"
						(effects
							(font
								(size 1.27 1.27)
							)
						)
					)
					(number "13"
						(effects
							(font
								(size 1.27 1.27)
							)
						)
					)
				)
				(pin input line
					(at 0 -17.78 0)
					(length 2.54)
					(name "~{RESET}"
						(effects
							(font
								(size 1.27 1.27)
							)
						)
					)
					(number "3"
						(effects
							(font
								(size 1.27 1.27)
							)
						)
					)
				)
				(pin input line
					(at 0 -20.32 0)
					(length 2.54)
					(name "ADDR"
						(effects
							(font
								(size 1.27 1.27)
							)
						)
					)
					(number "2"
						(effects
							(font
								(size 1.27 1.27)
							)
						)
					)
				)
				(pin power_in line
					(at 0 -25.4 0)
					(length 2.54)
					(name "GND"
						(effects
							(font
								(size 1.27 1.27)
							)
						)
					)
					(number "8"
						(effects
							(font
								(size 1.27 1.27)
							)
						)
					)
				)
				(pin bidirectional line
					(at 22.86 0 180)
					(length 2.54)
					(name "P0"
						(effects
							(font
								(size 1.27 1.27)
							)
						)
					)
					(number "4"
						(effects
							(font
								(size 1.27 1.27)
							)
						)
					)
				)
				(pin bidirectional line
					(at 22.86 -2.54 180)
					(length 2.54)
					(name "P1"
						(effects
							(font
								(size 1.27 1.27)
							)
						)
					)
					(number "5"
						(effects
							(font
								(size 1.27 1.27)
							)
						)
					)
				)
				(pin bidirectional line
					(at 22.86 -5.08 180)
					(length 2.54)
					(name "P2"
						(effects
							(font
								(size 1.27 1.27)
							)
						)
					)
					(number "6"
						(effects
							(font
								(size 1.27 1.27)
							)
						)
					)
				)
				(pin bidirectional line
					(at 22.86 -7.62 180)
					(length 2.54)
					(name "P3"
						(effects
							(font
								(size 1.27 1.27)
							)
						)
					)
					(number "7"
						(effects
							(font
								(size 1.27 1.27)
							)
						)
					)
				)
				(pin bidirectional line
					(at 22.86 -10.16 180)
					(length 2.54)
					(name "P4"
						(effects
							(font
								(size 1.27 1.27)
							)
						)
					)
					(number "9"
						(effects
							(font
								(size 1.27 1.27)
							)
						)
					)
				)
				(pin bidirectional line
					(at 22.86 -12.7 180)
					(length 2.54)
					(name "P5"
						(effects
							(font
								(size 1.27 1.27)
							)
						)
					)
					(number "10"
						(effects
							(font
								(size 1.27 1.27)
							)
						)
					)
				)
				(pin bidirectional line
					(at 22.86 -15.24 180)
					(length 2.54)
					(name "P6"
						(effects
							(font
								(size 1.27 1.27)
							)
						)
					)
					(number "11"
						(effects
							(font
								(size 1.27 1.27)
							)
						)
					)
				)
				(pin bidirectional line
					(at 22.86 -17.78 180)
					(length 2.54)
					(name "P7"
						(effects
							(font
								(size 1.27 1.27)
							)
						)
					)
					(number "12"
						(effects
							(font
								(size 1.27 1.27)
							)
						)
					)
				)
			)
		)
	(symbol "antmicroLEDIndicationDiscrete:LED_G_0603_KP-1608CGCK"
			(pin_names
				(hide yes)
			)
			(exclude_from_sim no)
			(in_bom yes)
			(on_board yes)
			(property "Reference" "D"
				(at 22.86 -5.08 0)
				(effects
					(font
						(size 1.27 1.27)
						(thickness 0.15)
					)
					(justify left bottom)
				)
			)
			(property "Value" "LED_G_0603_KP-1608CGCK"
				(at 22.86 -7.62 0)
				(effects
					(font
						(size 1.27 1.27)
						(thickness 0.15)
					)
					(justify left bottom)
				)
			)
			(property "Footprint" "antmicro-footprints:LED_0603_1608Metric_G"
				(at 22.86 -10.16 0)
				(effects
					(font
						(size 1.27 1.27)
						(thickness 0.15)
					)
					(justify left bottom)
					(hide yes)
				)
			)
			(property "Datasheet" "http://www.farnell.com/datasheets/2045956.pdf"
				(at 22.86 -12.7 0)
				(effects
					(font
						(size 1.27 1.27)
						(thickness 0.15)
					)
					(justify left bottom)
					(hide yes)
				)
			)
			(property "Description" ""
				(at 0 0 0)
				(effects
					(font
						(size 1.27 1.27)
					)
					(hide yes)
				)
			)
			(property "MPN" "KP-1608CGCK"
				(at 22.86 -15.24 0)
				(effects
					(font
						(size 1.27 1.27)
						(thickness 0.15)
					)
					(justify left bottom)
					(hide yes)
				)
			)
			(property "Manufacturer" "Kingbright"
				(at 22.86 -17.78 0)
				(effects
					(font
						(size 1.27 1.27)
						(thickness 0.15)
					)
					(justify left bottom)
					(hide yes)
				)
			)
			(property "Author" "Antmicro"
				(at 22.86 -20.32 0)
				(effects
					(font
						(size 1.27 1.27)
						(thickness 0.15)
					)
					(justify left bottom)
					(hide yes)
				)
			)
			(property "License" "Apache-2.0"
				(at 22.86 -22.86 0)
				(effects
					(font
						(size 1.27 1.27)
						(thickness 0.15)
					)
					(justify left bottom)
					(hide yes)
				)
			)
			(symbol "LED_G_0603_KP-1608CGCK_1_1"
				(polyline
					(pts
						(xy 2.54 1.27) (xy 2.54 -1.27) (xy 5.08 0) (xy 2.54 1.27)
					)
					(stroke
						(width 0.254)
						(type default)
					)
					(fill
						(type outline)
					)
				)
				(polyline
					(pts
						(xy 3.683 2.286) (xy 3.683 1.778) (xy 3.683 2.286) (xy 3.175 2.286) (xy 3.683 2.286) (xy 2.794 1.397)
					)
					(stroke
						(width 0.254)
						(type default)
					)
					(fill
						(type none)
					)
				)
				(polyline
					(pts
						(xy 4.699 2.032) (xy 4.699 1.524) (xy 4.699 2.032) (xy 4.191 2.032) (xy 4.699 2.032) (xy 3.683 1.016)
					)
					(stroke
						(width 0.254)
						(type default)
					)
					(fill
						(type none)
					)
				)
				(polyline
					(pts
						(xy 5.08 1.27) (xy 5.08 -1.27)
					)
					(stroke
						(width 0.254)
						(type default)
					)
					(fill
						(type none)
					)
				)
				(pin passive line
					(at 0 0 0)
					(length 2.54)
					(name "1"
						(effects
							(font
								(size 1.27 1.27)
							)
						)
					)
					(number "1"
						(effects
							(font
								(size 1.27 1.27)
							)
						)
					)
				)
				(pin passive line
					(at 7.62 0 180)
					(length 2.54)
					(name "2"
						(effects
							(font
								(size 1.27 1.27)
							)
						)
					)
					(number "2"
						(effects
							(font
								(size 1.27 1.27)
							)
						)
					)
				)
			)
		)
	(symbol "antmicroMechanicalParts:antmicro_logo"
			(exclude_from_sim no)
			(in_bom yes)
			(on_board yes)
			(property "Reference" "N"
				(at 15.24 -5.08 0)
				(effects
					(font
						(size 1.27 1.27)
						(thickness 0.15)
					)
					(justify left bottom)
				)
			)
			(property "Value" "antmicro_logo"
				(at 15.24 -7.62 0)
				(effects
					(font
						(size 1.27 1.27)
						(thickness 0.15)
					)
					(justify left bottom)
				)
			)
			(property "Footprint" "antmicro-footprints:antmicro-logo"
				(at 15.24 -10.16 0)
				(effects
					(font
						(size 1.27 1.27)
						(thickness 0.15)
					)
					(justify left bottom)
					(hide yes)
				)
			)
			(property "Datasheet" ""
				(at 15.24 -12.7 0)
				(effects
					(font
						(size 1.27 1.27)
						(thickness 0.15)
					)
					(justify left bottom)
					(hide yes)
				)
			)
			(property "Description" ""
				(at 0 0 0)
				(effects
					(font
						(size 1.27 1.27)
					)
					(hide yes)
				)
			)
			(property "MPN" ""
				(at 0 0 0)
				(effects
					(font
						(size 1.27 1.27)
					)
					(hide yes)
				)
			)
			(property "Manufacturer" ""
				(at 15.24 -20.32 0)
				(effects
					(font
						(size 1.27 1.27)
						(thickness 0.15)
					)
					(justify left bottom)
					(hide yes)
				)
			)
			(property "Author" "Antmicro"
				(at 15.24 -15.24 0)
				(effects
					(font
						(size 1.27 1.27)
						(thickness 0.15)
					)
					(justify left bottom)
					(hide yes)
				)
			)
			(property "License" "Apache-2.0"
				(at 15.24 -17.78 0)
				(effects
					(font
						(size 1.27 1.27)
						(thickness 0.15)
					)
					(justify left bottom)
					(hide yes)
				)
			)
			(symbol "antmicro_logo_1_1"
				(text "Logo"
					(at 0 0 0)
					(effects
						(font
							(size 1.27 1.27)
							(thickness 0.15)
						)
						(justify left bottom)
					)
				)
			)
		)
	(symbol "antmicroMechanicalParts:oshw_logo"
			(exclude_from_sim no)
			(in_bom yes)
			(on_board yes)
			(property "Reference" "N"
				(at 15.24 -5.08 0)
				(effects
					(font
						(size 1.27 1.27)
						(thickness 0.15)
					)
					(justify left bottom)
				)
			)
			(property "Value" "oshw_logo"
				(at 15.24 -7.62 0)
				(effects
					(font
						(size 1.27 1.27)
						(thickness 0.15)
					)
					(justify left bottom)
				)
			)
			(property "Footprint" "antmicro-footprints:oshw-logo"
				(at 15.24 -10.16 0)
				(effects
					(font
						(size 1.27 1.27)
						(thickness 0.15)
					)
					(justify left bottom)
					(hide yes)
				)
			)
			(property "Datasheet" ""
				(at 15.24 -12.7 0)
				(effects
					(font
						(size 1.27 1.27)
						(thickness 0.15)
					)
					(justify left bottom)
					(hide yes)
				)
			)
			(property "Description" ""
				(at 0 0 0)
				(effects
					(font
						(size 1.27 1.27)
					)
					(hide yes)
				)
			)
			(property "Author" "Antmicro"
				(at 15.24 -15.24 0)
				(effects
					(font
						(size 1.27 1.27)
						(thickness 0.15)
					)
					(justify left bottom)
					(hide yes)
				)
			)
			(property "License" "Apache-2.0"
				(at 15.24 -17.78 0)
				(effects
					(font
						(size 1.27 1.27)
						(thickness 0.15)
					)
					(justify left bottom)
					(hide yes)
				)
			)
			(property "MPN" ""
				(at 0 0 0)
				(effects
					(font
						(size 1.27 1.27)
					)
					(hide yes)
				)
			)
			(property "Manufacturer" ""
				(at 15.24 -20.32 0)
				(effects
					(font
						(size 1.27 1.27)
						(thickness 0.15)
					)
					(justify left bottom)
					(hide yes)
				)
			)
			(symbol "oshw_logo_1_1"
				(text "Logo"
					(at 0 0 0)
					(effects
						(font
							(size 1.27 1.27)
							(thickness 0.15)
						)
						(justify left bottom)
					)
				)
			)
		)
	(symbol "antmicroMemory:AT24CS01_SOT23"
			(exclude_from_sim no)
			(in_bom yes)
			(on_board yes)
			(property "Reference" "U"
				(at 35.56 -2.54 0)
				(effects
					(font
						(size 1.27 1.27)
						(thickness 0.15)
					)
					(justify left bottom)
				)
			)
			(property "Value" "AT24CS01_SOT23"
				(at 35.56 -5.08 0)
				(effects
					(font
						(size 1.27 1.27)
						(thickness 0.15)
					)
					(justify left bottom)
				)
			)
			(property "Footprint" "antmicro-footprints:SOT-23-5"
				(at 35.56 -7.62 0)
				(effects
					(font
						(size 1.27 1.27)
						(thickness 0.15)
					)
					(justify left bottom)
					(hide yes)
				)
			)
			(property "Datasheet" "http://ww1.microchip.com/downloads/en/devicedoc/Atmel-8815-SEEPROM-AT24CS01-02-Datasheet.pdf"
				(at 35.56 -10.16 0)
				(effects
					(font
						(size 1.27 1.27)
						(thickness 0.15)
					)
					(justify left bottom)
					(hide yes)
				)
			)
			(property "Description" "SOT-23-5"
				(at 0 0 0)
				(effects
					(font
						(size 1.27 1.27)
					)
					(hide yes)
				)
			)
			(property "Manufacturer" "Atmel"
				(at 35.56 -12.7 0)
				(effects
					(font
						(size 1.27 1.27)
						(thickness 0.15)
					)
					(justify left bottom)
					(hide yes)
				)
			)
			(property "MPN" "AT24CS01-ST"
				(at 35.56 -15.24 0)
				(effects
					(font
						(size 1.27 1.27)
						(thickness 0.15)
					)
					(justify left bottom)
					(hide yes)
				)
			)
			(property "Author" "Antmicro"
				(at 35.56 -17.78 0)
				(effects
					(font
						(size 1.27 1.27)
						(thickness 0.15)
					)
					(justify left bottom)
					(hide yes)
				)
			)
			(property "License" "Apache-2.0"
				(at 35.56 -20.32 0)
				(effects
					(font
						(size 1.27 1.27)
						(thickness 0.15)
					)
					(justify left bottom)
					(hide yes)
				)
			)
			(property "ki_keywords" "SOT-23-5"
				(at 0 0 0)
				(effects
					(font
						(size 1.27 1.27)
					)
					(hide yes)
				)
			)
			(symbol "AT24CS01_SOT23_1_1"
				(rectangle
					(start 2.54 -7.62)
					(end 17.78 2.54)
					(stroke
						(width 0.254)
						(type default)
					)
					(fill
						(type background)
					)
				)
				(pin passive line
					(at 0 0 0)
					(length 2.54)
					(name "SDA"
						(effects
							(font
								(size 1.27 1.27)
							)
						)
					)
					(number "3"
						(effects
							(font
								(size 1.27 1.27)
							)
						)
					)
				)
				(pin passive line
					(at 0 -2.54 0)
					(length 2.54)
					(name "SCL"
						(effects
							(font
								(size 1.27 1.27)
							)
						)
					)
					(number "1"
						(effects
							(font
								(size 1.27 1.27)
							)
						)
					)
				)
				(pin passive line
					(at 0 -5.08 0)
					(length 2.54)
					(name "WP"
						(effects
							(font
								(size 1.27 1.27)
							)
						)
					)
					(number "5"
						(effects
							(font
								(size 1.27 1.27)
							)
						)
					)
				)
				(pin passive line
					(at 20.32 0 180)
					(length 2.54)
					(name "VCC"
						(effects
							(font
								(size 1.27 1.27)
							)
						)
					)
					(number "4"
						(effects
							(font
								(size 1.27 1.27)
							)
						)
					)
				)
				(pin passive line
					(at 20.32 -2.54 180)
					(length 2.54)
					(name "GND"
						(effects
							(font
								(size 1.27 1.27)
							)
						)
					)
					(number "2"
						(effects
							(font
								(size 1.27 1.27)
							)
						)
					)
				)
			)
		)
	(symbol "antmicroMemory:MT60B2G8HB-48B_A"
			(exclude_from_sim no)
			(in_bom yes)
			(on_board yes)
			(property "Reference" "U"
				(at 52.07 -6.35 0)
				(effects
					(font
						(size 1.27 1.27)
						(thickness 0.15)
					)
					(justify left bottom)
				)
			)
			(property "Value" "MT60B2G8HB-48B_A"
				(at 52.07 -8.89 0)
				(effects
					(font
						(size 1.27 1.27)
						(thickness 0.15)
					)
					(justify left bottom)
					(hide yes)
				)
			)
			(property "Footprint" "antmicro-footprints:BGA-82_11x9mm_Layout13x11_P0.8mm_DDR5_MO-210-AN"
				(at 52.07 -11.43 0)
				(effects
					(font
						(size 1.27 1.27)
						(thickness 0.15)
					)
					(justify left bottom)
					(hide yes)
				)
			)
			(property "Datasheet" "https://www.farnell.com/datasheets/3704816.pdf"
				(at 52.07 -13.97 0)
				(effects
					(font
						(size 1.27 1.27)
						(thickness 0.15)
					)
					(justify left bottom)
					(hide yes)
				)
			)
			(property "Description" "DRAM, SDRAM, 16 Gbit, 2G x 8bit, FBGA, 82 Pins"
				(at 0 0 0)
				(effects
					(font
						(size 1.27 1.27)
					)
					(hide yes)
				)
			)
			(property "Manufacturer" "Micron Technology"
				(at 52.07 -16.51 0)
				(effects
					(font
						(size 1.27 1.27)
						(thickness 0.15)
					)
					(justify left bottom)
					(hide yes)
				)
			)
			(property "MPN" "MT60B2G8HB-48B:A"
				(at 52.07 -19.05 0)
				(effects
					(font
						(size 1.27 1.27)
						(thickness 0.15)
					)
					(justify left bottom)
				)
			)
			(property "Author" "Antmicro"
				(at 52.07 -21.59 0)
				(effects
					(font
						(size 1.27 1.27)
						(thickness 0.15)
					)
					(justify left bottom)
					(hide yes)
				)
			)
			(property "License" "Apache-2.0"
				(at 52.07 -24.13 0)
				(effects
					(font
						(size 1.27 1.27)
						(thickness 0.15)
					)
					(justify left bottom)
					(hide yes)
				)
			)
			(property "ki_keywords" "SMT, DRAM, IC"
				(at 0 0 0)
				(effects
					(font
						(size 1.27 1.27)
					)
					(hide yes)
				)
			)
			(property "ki_fp_filters" "BGA*10.0x14.5mm*P0.80x0.65mm*"
				(at 0 0 0)
				(effects
					(font
						(size 1.27 1.27)
					)
					(hide yes)
				)
			)
			(symbol "MT60B2G8HB-48B_A_1_1"
				(rectangle
					(start 3.81 -63.5)
					(end 34.29 2.54)
					(stroke
						(width 0.254)
						(type default)
					)
					(fill
						(type background)
					)
				)
				(pin power_in line
					(at 0 0 0)
					(length 3.81)
					(name "VDD"
						(effects
							(font
								(size 1.27 1.27)
							)
						)
					)
					(number "B10"
						(effects
							(font
								(size 1.27 1.27)
							)
						)
					)
				)
				(pin power_in line
					(at 0 0 0)
					(length 3.81)
					(hide yes)
					(name "VDD"
						(effects
							(font
								(size 1.27 1.27)
							)
						)
					)
					(number "B2"
						(effects
							(font
								(size 1.27 1.27)
							)
						)
					)
				)
				(pin power_in line
					(at 0 0 0)
					(length 3.81)
					(hide yes)
					(name "VDD"
						(effects
							(font
								(size 1.27 1.27)
							)
						)
					)
					(number "E10"
						(effects
							(font
								(size 1.27 1.27)
							)
						)
					)
				)
				(pin power_in line
					(at 0 0 0)
					(length 3.81)
					(hide yes)
					(name "VDD"
						(effects
							(font
								(size 1.27 1.27)
							)
						)
					)
					(number "E2"
						(effects
							(font
								(size 1.27 1.27)
							)
						)
					)
				)
				(pin power_in line
					(at 0 0 0)
					(length 3.81)
					(hide yes)
					(name "VDD"
						(effects
							(font
								(size 1.27 1.27)
							)
						)
					)
					(number "G4"
						(effects
							(font
								(size 1.27 1.27)
							)
						)
					)
				)
				(pin power_in line
					(at 0 0 0)
					(length 3.81)
					(hide yes)
					(name "VDD"
						(effects
							(font
								(size 1.27 1.27)
							)
						)
					)
					(number "H10"
						(effects
							(font
								(size 1.27 1.27)
							)
						)
					)
				)
				(pin power_in line
					(at 0 0 0)
					(length 3.81)
					(hide yes)
					(name "VDD"
						(effects
							(font
								(size 1.27 1.27)
							)
						)
					)
					(number "K10"
						(effects
							(font
								(size 1.27 1.27)
							)
						)
					)
				)
				(pin power_in line
					(at 0 0 0)
					(length 3.81)
					(hide yes)
					(name "VDD"
						(effects
							(font
								(size 1.27 1.27)
							)
						)
					)
					(number "K2"
						(effects
							(font
								(size 1.27 1.27)
							)
						)
					)
				)
				(pin power_in line
					(at 0 0 0)
					(length 3.81)
					(hide yes)
					(name "VDD"
						(effects
							(font
								(size 1.27 1.27)
							)
						)
					)
					(number "N10"
						(effects
							(font
								(size 1.27 1.27)
							)
						)
					)
				)
				(pin power_in line
					(at 0 0 0)
					(length 3.81)
					(hide yes)
					(name "VDD"
						(effects
							(font
								(size 1.27 1.27)
							)
						)
					)
					(number "N2"
						(effects
							(font
								(size 1.27 1.27)
							)
						)
					)
				)
				(pin power_in line
					(at 0 0 0)
					(length 3.81)
					(hide yes)
					(name "VDD"
						(effects
							(font
								(size 1.27 1.27)
							)
						)
					)
					(number "N4"
						(effects
							(font
								(size 1.27 1.27)
							)
						)
					)
				)
				(pin power_in line
					(at 0 -2.54 0)
					(length 3.81)
					(name "VPP"
						(effects
							(font
								(size 1.27 1.27)
							)
						)
					)
					(number "A4"
						(effects
							(font
								(size 1.27 1.27)
							)
						)
					)
				)
				(pin power_in line
					(at 0 -2.54 0)
					(length 3.81)
					(hide yes)
					(name "VPP"
						(effects
							(font
								(size 1.27 1.27)
							)
						)
					)
					(number "N8"
						(effects
							(font
								(size 1.27 1.27)
							)
						)
					)
				)
				(pin power_in line
					(at 0 -5.08 0)
					(length 3.81)
					(name "VDDQ"
						(effects
							(font
								(size 1.27 1.27)
							)
						)
					)
					(number "B3"
						(effects
							(font
								(size 1.27 1.27)
							)
						)
					)
				)
				(pin power_in line
					(at 0 -5.08 0)
					(length 3.81)
					(hide yes)
					(name "VDDQ"
						(effects
							(font
								(size 1.27 1.27)
							)
						)
					)
					(number "B9"
						(effects
							(font
								(size 1.27 1.27)
							)
						)
					)
				)
				(pin power_in line
					(at 0 -5.08 0)
					(length 3.81)
					(hide yes)
					(name "VDDQ"
						(effects
							(font
								(size 1.27 1.27)
							)
						)
					)
					(number "D10"
						(effects
							(font
								(size 1.27 1.27)
							)
						)
					)
				)
				(pin power_in line
					(at 0 -5.08 0)
					(length 3.81)
					(hide yes)
					(name "VDDQ"
						(effects
							(font
								(size 1.27 1.27)
							)
						)
					)
					(number "D2"
						(effects
							(font
								(size 1.27 1.27)
							)
						)
					)
				)
				(pin power_in line
					(at 0 -5.08 0)
					(length 3.81)
					(hide yes)
					(name "VDDQ"
						(effects
							(font
								(size 1.27 1.27)
							)
						)
					)
					(number "F3"
						(effects
							(font
								(size 1.27 1.27)
							)
						)
					)
				)
				(pin power_in line
					(at 0 -5.08 0)
					(length 3.81)
					(hide yes)
					(name "VDDQ"
						(effects
							(font
								(size 1.27 1.27)
							)
						)
					)
					(number "F9"
						(effects
							(font
								(size 1.27 1.27)
							)
						)
					)
				)
				(pin power_in line
					(at 0 -5.08 0)
					(length 3.81)
					(hide yes)
					(name "VDDQ"
						(effects
							(font
								(size 1.27 1.27)
							)
						)
					)
					(number "G9"
						(effects
							(font
								(size 1.27 1.27)
							)
						)
					)
				)
				(pin power_in line
					(at 0 -5.08 0)
					(length 3.81)
					(hide yes)
					(name "VDDQ"
						(effects
							(font
								(size 1.27 1.27)
							)
						)
					)
					(number "J10"
						(effects
							(font
								(size 1.27 1.27)
							)
						)
					)
				)
				(pin power_in line
					(at 0 -5.08 0)
					(length 3.81)
					(hide yes)
					(name "VDDQ"
						(effects
							(font
								(size 1.27 1.27)
							)
						)
					)
					(number "J2"
						(effects
							(font
								(size 1.27 1.27)
							)
						)
					)
				)
				(pin power_in line
					(at 0 -5.08 0)
					(length 3.81)
					(hide yes)
					(name "VDDQ"
						(effects
							(font
								(size 1.27 1.27)
							)
						)
					)
					(number "L10"
						(effects
							(font
								(size 1.27 1.27)
							)
						)
					)
				)
				(pin power_in line
					(at 0 -5.08 0)
					(length 3.81)
					(hide yes)
					(name "VDDQ"
						(effects
							(font
								(size 1.27 1.27)
							)
						)
					)
					(number "L2"
						(effects
							(font
								(size 1.27 1.27)
							)
						)
					)
				)
				(pin input line
					(at 0 -7.62 0)
					(length 3.81)
					(name "CK_T"
						(effects
							(font
								(size 1.27 1.27)
							)
						)
					)
					(number "G8"
						(effects
							(font
								(size 1.27 1.27)
							)
						)
					)
				)
				(pin input line
					(at 0 -10.16 0)
					(length 3.81)
					(name "CK_C"
						(effects
							(font
								(size 1.27 1.27)
							)
						)
					)
					(number "H8"
						(effects
							(font
								(size 1.27 1.27)
							)
						)
					)
				)
				(pin input line
					(at 0 -15.24 0)
					(length 3.81)
					(name "CS_N"
						(effects
							(font
								(size 1.27 1.27)
							)
						)
					)
					(number "H4"
						(effects
							(font
								(size 1.27 1.27)
							)
						)
					)
				)
				(pin bidirectional line
					(at 0 -17.78 0)
					(length 3.81)
					(name "CA0"
						(effects
							(font
								(size 1.27 1.27)
							)
						)
					)
					(number "J4"
						(effects
							(font
								(size 1.27 1.27)
							)
						)
					)
				)
				(pin bidirectional line
					(at 0 -20.32 0)
					(length 3.81)
					(name "CA1"
						(effects
							(font
								(size 1.27 1.27)
							)
						)
					)
					(number "J8"
						(effects
							(font
								(size 1.27 1.27)
							)
						)
					)
				)
				(pin bidirectional line
					(at 0 -22.86 0)
					(length 3.81)
					(name "CA2"
						(effects
							(font
								(size 1.27 1.27)
							)
						)
					)
					(number "K4"
						(effects
							(font
								(size 1.27 1.27)
							)
						)
					)
				)
				(pin bidirectional line
					(at 0 -25.4 0)
					(length 3.81)
					(name "CA3"
						(effects
							(font
								(size 1.27 1.27)
							)
						)
					)
					(number "K8"
						(effects
							(font
								(size 1.27 1.27)
							)
						)
					)
				)
				(pin bidirectional line
					(at 0 -27.94 0)
					(length 3.81)
					(name "CA4"
						(effects
							(font
								(size 1.27 1.27)
							)
						)
					)
					(number "J3"
						(effects
							(font
								(size 1.27 1.27)
							)
						)
					)
				)
				(pin bidirectional line
					(at 0 -30.48 0)
					(length 3.81)
					(name "CA5"
						(effects
							(font
								(size 1.27 1.27)
							)
						)
					)
					(number "J9"
						(effects
							(font
								(size 1.27 1.27)
							)
						)
					)
				)
				(pin bidirectional line
					(at 0 -33.02 0)
					(length 3.81)
					(name "CA6"
						(effects
							(font
								(size 1.27 1.27)
							)
						)
					)
					(number "K3"
						(effects
							(font
								(size 1.27 1.27)
							)
						)
					)
				)
				(pin bidirectional line
					(at 0 -35.56 0)
					(length 3.81)
					(name "CA7"
						(effects
							(font
								(size 1.27 1.27)
							)
						)
					)
					(number "K9"
						(effects
							(font
								(size 1.27 1.27)
							)
						)
					)
				)
				(pin bidirectional line
					(at 0 -38.1 0)
					(length 3.81)
					(name "CA8"
						(effects
							(font
								(size 1.27 1.27)
							)
						)
					)
					(number "L4"
						(effects
							(font
								(size 1.27 1.27)
							)
						)
					)
				)
				(pin bidirectional line
					(at 0 -40.64 0)
					(length 3.81)
					(name "CA9"
						(effects
							(font
								(size 1.27 1.27)
							)
						)
					)
					(number "L8"
						(effects
							(font
								(size 1.27 1.27)
							)
						)
					)
				)
				(pin bidirectional line
					(at 0 -43.18 0)
					(length 3.81)
					(name "CA10"
						(effects
							(font
								(size 1.27 1.27)
							)
						)
					)
					(number "M3"
						(effects
							(font
								(size 1.27 1.27)
							)
						)
					)
				)
				(pin bidirectional line
					(at 0 -45.72 0)
					(length 3.81)
					(name "CA11"
						(effects
							(font
								(size 1.27 1.27)
							)
						)
					)
					(number "M9"
						(effects
							(font
								(size 1.27 1.27)
							)
						)
					)
				)
				(pin bidirectional line
					(at 0 -48.26 0)
					(length 3.81)
					(name "CA12"
						(effects
							(font
								(size 1.27 1.27)
							)
						)
					)
					(number "M4"
						(effects
							(font
								(size 1.27 1.27)
							)
						)
					)
				)
				(pin bidirectional line
					(at 0 -50.8 0)
					(length 3.81)
					(name "CA13"
						(effects
							(font
								(size 1.27 1.27)
							)
						)
					)
					(number "M8"
						(effects
							(font
								(size 1.27 1.27)
							)
						)
					)
				)
				(pin bidirectional line
					(at 0 -55.88 0)
					(length 3.81)
					(name "DQS_T"
						(effects
							(font
								(size 1.27 1.27)
							)
						)
					)
					(number "C4"
						(effects
							(font
								(size 1.27 1.27)
							)
						)
					)
				)
				(pin bidirectional line
					(at 0 -58.42 0)
					(length 3.81)
					(name "DQS_C"
						(effects
							(font
								(size 1.27 1.27)
							)
						)
					)
					(number "D4"
						(effects
							(font
								(size 1.27 1.27)
							)
						)
					)
				)
				(pin input line
					(at 0 -60.96 0)
					(length 3.81)
					(name "ZQ"
						(effects
							(font
								(size 1.27 1.27)
							)
						)
					)
					(number "A8"
						(effects
							(font
								(size 1.27 1.27)
							)
						)
					)
				)
				(pin no_connect line
					(at 34.29 -15.24 180)
					(length 3.81)
					(hide yes)
					(name "DNU"
						(effects
							(font
								(size 1.27 1.27)
							)
						)
					)
					(number "N11"
						(effects
							(font
								(size 1.27 1.27)
							)
						)
					)
				)
				(pin no_connect line
					(at 34.29 -17.78 180)
					(length 3.81)
					(hide yes)
					(name "DNU"
						(effects
							(font
								(size 1.27 1.27)
							)
						)
					)
					(number "N1"
						(effects
							(font
								(size 1.27 1.27)
							)
						)
					)
				)
				(pin no_connect line
					(at 34.29 -20.32 180)
					(length 3.81)
					(hide yes)
					(name "DNU"
						(effects
							(font
								(size 1.27 1.27)
							)
						)
					)
					(number "A11"
						(effects
							(font
								(size 1.27 1.27)
							)
						)
					)
				)
				(pin no_connect line
					(at 34.29 -22.86 180)
					(length 3.81)
					(hide yes)
					(name "DNU"
						(effects
							(font
								(size 1.27 1.27)
							)
						)
					)
					(number "A1"
						(effects
							(font
								(size 1.27 1.27)
							)
						)
					)
				)
				(pin input line
					(at 38.1 0 180)
					(length 3.81)
					(name "RESET_N"
						(effects
							(font
								(size 1.27 1.27)
							)
						)
					)
					(number "M10"
						(effects
							(font
								(size 1.27 1.27)
							)
						)
					)
				)
				(pin input line
					(at 38.1 -2.54 180)
					(length 3.81)
					(name "CA_ODT"
						(effects
							(font
								(size 1.27 1.27)
							)
						)
					)
					(number "G2"
						(effects
							(font
								(size 1.27 1.27)
							)
						)
					)
				)
				(pin bidirectional line
					(at 38.1 -5.08 180)
					(length 3.81)
					(name "ALERT_N"
						(effects
							(font
								(size 1.27 1.27)
							)
						)
					)
					(number "H2"
						(effects
							(font
								(size 1.27 1.27)
							)
						)
					)
				)
				(pin input line
					(at 38.1 -7.62 180)
					(length 3.81)
					(name "CAI"
						(effects
							(font
								(size 1.27 1.27)
							)
						)
					)
					(number "M2"
						(effects
							(font
								(size 1.27 1.27)
							)
						)
					)
				)
				(pin input line
					(at 38.1 -10.16 180)
					(length 3.81)
					(name "MIR"
						(effects
							(font
								(size 1.27 1.27)
							)
						)
					)
					(number "G3"
						(effects
							(font
								(size 1.27 1.27)
							)
						)
					)
				)
				(pin input line
					(at 38.1 -12.7 180)
					(length 3.81)
					(name "TEN"
						(effects
							(font
								(size 1.27 1.27)
							)
						)
					)
					(number "G10"
						(effects
							(font
								(size 1.27 1.27)
							)
						)
					)
				)
				(pin bidirectional line
					(at 38.1 -25.4 180)
					(length 3.81)
					(name "DQ0"
						(effects
							(font
								(size 1.27 1.27)
							)
						)
					)
					(number "C3"
						(effects
							(font
								(size 1.27 1.27)
							)
						)
					)
				)
				(pin bidirectional line
					(at 38.1 -27.94 180)
					(length 3.81)
					(name "DQ1"
						(effects
							(font
								(size 1.27 1.27)
							)
						)
					)
					(number "C9"
						(effects
							(font
								(size 1.27 1.27)
							)
						)
					)
				)
				(pin bidirectional line
					(at 38.1 -30.48 180)
					(length 3.81)
					(name "DQ2"
						(effects
							(font
								(size 1.27 1.27)
							)
						)
					)
					(number "B4"
						(effects
							(font
								(size 1.27 1.27)
							)
						)
					)
				)
				(pin bidirectional line
					(at 38.1 -33.02 180)
					(length 3.81)
					(name "DQ3"
						(effects
							(font
								(size 1.27 1.27)
							)
						)
					)
					(number "B8"
						(effects
							(font
								(size 1.27 1.27)
							)
						)
					)
				)
				(pin bidirectional line
					(at 38.1 -35.56 180)
					(length 3.81)
					(name "DQ4"
						(effects
							(font
								(size 1.27 1.27)
							)
						)
					)
					(number "E3"
						(effects
							(font
								(size 1.27 1.27)
							)
						)
					)
				)
				(pin bidirectional line
					(at 38.1 -38.1 180)
					(length 3.81)
					(name "DQ5"
						(effects
							(font
								(size 1.27 1.27)
							)
						)
					)
					(number "E9"
						(effects
							(font
								(size 1.27 1.27)
							)
						)
					)
				)
				(pin bidirectional line
					(at 38.1 -40.64 180)
					(length 3.81)
					(name "DQ6"
						(effects
							(font
								(size 1.27 1.27)
							)
						)
					)
					(number "E4"
						(effects
							(font
								(size 1.27 1.27)
							)
						)
					)
				)
				(pin bidirectional line
					(at 38.1 -43.18 180)
					(length 3.81)
					(name "DQ7"
						(effects
							(font
								(size 1.27 1.27)
							)
						)
					)
					(number "E8"
						(effects
							(font
								(size 1.27 1.27)
							)
						)
					)
				)
				(pin output line
					(at 38.1 -48.26 180)
					(length 3.81)
					(name "TDQS_T"
						(effects
							(font
								(size 1.27 1.27)
							)
						)
					)
					(number "C8"
						(effects
							(font
								(size 1.27 1.27)
							)
						)
					)
				)
				(pin output line
					(at 38.1 -50.8 180)
					(length 3.81)
					(name "TDQS_C"
						(effects
							(font
								(size 1.27 1.27)
							)
						)
					)
					(number "D8"
						(effects
							(font
								(size 1.27 1.27)
							)
						)
					)
				)
				(pin input line
					(at 38.1 -55.88 180)
					(length 3.81)
					(name "LBDQ"
						(effects
							(font
								(size 1.27 1.27)
							)
						)
					)
					(number "A2"
						(effects
							(font
								(size 1.27 1.27)
							)
						)
					)
				)
				(pin input line
					(at 38.1 -58.42 180)
					(length 3.81)
					(name "LBDQS"
						(effects
							(font
								(size 1.27 1.27)
							)
						)
					)
					(number "A10"
						(effects
							(font
								(size 1.27 1.27)
							)
						)
					)
				)
				(pin passive line
					(at 38.1 -60.96 180)
					(length 3.81)
					(name "VSS"
						(effects
							(font
								(size 1.27 1.27)
							)
						)
					)
					(number "A3"
						(effects
							(font
								(size 1.27 1.27)
							)
						)
					)
				)
				(pin passive line
					(at 38.1 -60.96 180)
					(length 3.81)
					(hide yes)
					(name "VSS"
						(effects
							(font
								(size 1.27 1.27)
							)
						)
					)
					(number "A9"
						(effects
							(font
								(size 1.27 1.27)
							)
						)
					)
				)
				(pin passive line
					(at 38.1 -60.96 180)
					(length 3.81)
					(hide yes)
					(name "VSS"
						(effects
							(font
								(size 1.27 1.27)
							)
						)
					)
					(number "C10"
						(effects
							(font
								(size 1.27 1.27)
							)
						)
					)
				)
				(pin passive line
					(at 38.1 -60.96 180)
					(length 3.81)
					(hide yes)
					(name "VSS"
						(effects
							(font
								(size 1.27 1.27)
							)
						)
					)
					(number "C2"
						(effects
							(font
								(size 1.27 1.27)
							)
						)
					)
				)
				(pin passive line
					(at 38.1 -60.96 180)
					(length 3.81)
					(hide yes)
					(name "VSS"
						(effects
							(font
								(size 1.27 1.27)
							)
						)
					)
					(number "D3"
						(effects
							(font
								(size 1.27 1.27)
							)
						)
					)
				)
				(pin passive line
					(at 38.1 -60.96 180)
					(length 3.81)
					(hide yes)
					(name "VSS"
						(effects
							(font
								(size 1.27 1.27)
							)
						)
					)
					(number "D9"
						(effects
							(font
								(size 1.27 1.27)
							)
						)
					)
				)
				(pin passive line
					(at 38.1 -60.96 180)
					(length 3.81)
					(hide yes)
					(name "VSS"
						(effects
							(font
								(size 1.27 1.27)
							)
						)
					)
					(number "F10"
						(effects
							(font
								(size 1.27 1.27)
							)
						)
					)
				)
				(pin passive line
					(at 38.1 -60.96 180)
					(length 3.81)
					(hide yes)
					(name "VSS"
						(effects
							(font
								(size 1.27 1.27)
							)
						)
					)
					(number "F2"
						(effects
							(font
								(size 1.27 1.27)
							)
						)
					)
				)
				(pin passive line
					(at 38.1 -60.96 180)
					(length 3.81)
					(hide yes)
					(name "VSS"
						(effects
							(font
								(size 1.27 1.27)
							)
						)
					)
					(number "F4"
						(effects
							(font
								(size 1.27 1.27)
							)
						)
					)
				)
				(pin passive line
					(at 38.1 -60.96 180)
					(length 3.81)
					(hide yes)
					(name "VSS"
						(effects
							(font
								(size 1.27 1.27)
							)
						)
					)
					(number "F8"
						(effects
							(font
								(size 1.27 1.27)
							)
						)
					)
				)
				(pin passive line
					(at 38.1 -60.96 180)
					(length 3.81)
					(hide yes)
					(name "VSS"
						(effects
							(font
								(size 1.27 1.27)
							)
						)
					)
					(number "H3"
						(effects
							(font
								(size 1.27 1.27)
							)
						)
					)
				)
				(pin passive line
					(at 38.1 -60.96 180)
					(length 3.81)
					(hide yes)
					(name "VSS"
						(effects
							(font
								(size 1.27 1.27)
							)
						)
					)
					(number "H9"
						(effects
							(font
								(size 1.27 1.27)
							)
						)
					)
				)
				(pin passive line
					(at 38.1 -60.96 180)
					(length 3.81)
					(hide yes)
					(name "VSS"
						(effects
							(font
								(size 1.27 1.27)
							)
						)
					)
					(number "L3"
						(effects
							(font
								(size 1.27 1.27)
							)
						)
					)
				)
				(pin passive line
					(at 38.1 -60.96 180)
					(length 3.81)
					(hide yes)
					(name "VSS"
						(effects
							(font
								(size 1.27 1.27)
							)
						)
					)
					(number "L9"
						(effects
							(font
								(size 1.27 1.27)
							)
						)
					)
				)
				(pin passive line
					(at 38.1 -60.96 180)
					(length 3.81)
					(hide yes)
					(name "VSS"
						(effects
							(font
								(size 1.27 1.27)
							)
						)
					)
					(number "N3"
						(effects
							(font
								(size 1.27 1.27)
							)
						)
					)
				)
				(pin passive line
					(at 38.1 -60.96 180)
					(length 3.81)
					(hide yes)
					(name "VSS"
						(effects
							(font
								(size 1.27 1.27)
							)
						)
					)
					(number "N9"
						(effects
							(font
								(size 1.27 1.27)
							)
						)
					)
				)
			)
		)
	(symbol "antmicroResistors0402:R_0R_0402"
			(pin_numbers
				(hide yes)
			)
			(pin_names
				(hide yes)
			)
			(exclude_from_sim no)
			(in_bom yes)
			(on_board yes)
			(property "Reference" "R"
				(at 20.32 -5.08 0)
				(effects
					(font
						(size 1.27 1.27)
						(thickness 0.15)
					)
					(justify left bottom)
				)
			)
			(property "Value" "R_0R_0402"
				(at 20.32 -12.7 0)
				(effects
					(font
						(size 1.27 1.27)
						(thickness 0.15)
					)
					(justify left bottom)
					(hide yes)
				)
			)
			(property "Footprint" "antmicro-footprints:R_0402_1005Metric"
				(at 20.32 -15.24 0)
				(effects
					(font
						(size 1.27 1.27)
						(thickness 0.15)
					)
					(justify left bottom)
					(hide yes)
				)
			)
			(property "Datasheet" "https://industrial.panasonic.com/cdbs/www-data/pdf/RDA0000/AOA0000C301.pdf"
				(at 20.32 -17.78 0)
				(effects
					(font
						(size 1.27 1.27)
						(thickness 0.15)
					)
					(justify left bottom)
					(hide yes)
				)
			)
			(property "Description" "0R resistor in 0402 package with unspecified tolerance"
				(at 0 0 0)
				(effects
					(font
						(size 1.27 1.27)
					)
					(hide yes)
				)
			)
			(property "MPN" "ERJ2GE0R00X"
				(at 20.32 -20.32 0)
				(effects
					(font
						(size 1.27 1.27)
						(thickness 0.15)
					)
					(justify left bottom)
					(hide yes)
				)
			)
			(property "Manufacturer" "Panasonic"
				(at 20.32 -22.86 0)
				(effects
					(font
						(size 1.27 1.27)
						(thickness 0.15)
					)
					(justify left bottom)
					(hide yes)
				)
			)
			(property "License" "Apache-2.0"
				(at 20.32 -25.4 0)
				(effects
					(font
						(size 1.27 1.27)
						(thickness 0.15)
					)
					(justify left bottom)
					(hide yes)
				)
			)
			(property "Author" "Antmicro"
				(at 20.32 -27.94 0)
				(effects
					(font
						(size 1.27 1.27)
						(thickness 0.15)
					)
					(justify left bottom)
					(hide yes)
				)
			)
			(property "Val" "0R"
				(at 20.32 -7.62 0)
				(effects
					(font
						(size 1.27 1.27)
						(thickness 0.15)
					)
					(justify left bottom)
				)
			)
			(property "Tolerance" "~"
				(at 20.32 -10.16 0)
				(effects
					(font
						(size 1.27 1.27)
					)
					(justify left bottom)
					(hide yes)
				)
			)
			(property "Current" "1A"
				(at 20.32 -30.48 0)
				(effects
					(font
						(size 1.27 1.27)
						(thickness 0.15)
					)
					(justify left bottom)
					(hide yes)
				)
			)
			(symbol "R_0R_0402_0_1"
				(rectangle
					(start 0.635 0.889)
					(end 4.445 -0.889)
					(stroke
						(width 0.254)
						(type default)
					)
					(fill
						(type none)
					)
				)
			)
			(symbol "R_0R_0402_1_1"
				(pin passive line
					(at 0 0 0)
					(length 0.635)
					(name "~"
						(effects
							(font
								(size 1.27 1.27)
							)
						)
					)
					(number "1"
						(effects
							(font
								(size 1.27 1.27)
							)
						)
					)
				)
				(pin passive line
					(at 5.08 0 180)
					(length 0.635)
					(name "~"
						(effects
							(font
								(size 1.27 1.27)
							)
						)
					)
					(number "2"
						(effects
							(font
								(size 1.27 1.27)
							)
						)
					)
				)
			)
		)
	(symbol "antmicroResistors0402:R_10k_0402"
			(pin_numbers
				(hide yes)
			)
			(pin_names
				(hide yes)
			)
			(exclude_from_sim no)
			(in_bom yes)
			(on_board yes)
			(property "Reference" "R"
				(at 20.32 -5.08 0)
				(effects
					(font
						(size 1.27 1.27)
						(thickness 0.15)
					)
					(justify left bottom)
				)
			)
			(property "Value" "R_10k_0402"
				(at 20.32 -12.7 0)
				(effects
					(font
						(size 1.27 1.27)
						(thickness 0.15)
					)
					(justify left bottom)
					(hide yes)
				)
			)
			(property "Footprint" "antmicro-footprints:R_0402_1005Metric"
				(at 20.32 -15.24 0)
				(effects
					(font
						(size 1.27 1.27)
						(thickness 0.15)
					)
					(justify left bottom)
					(hide yes)
				)
			)
			(property "Datasheet" "https://www.bourns.com/docs/product-datasheets/cr.pdf"
				(at 20.32 -17.78 0)
				(effects
					(font
						(size 1.27 1.27)
						(thickness 0.15)
					)
					(justify left bottom)
					(hide yes)
				)
			)
			(property "Description" "10k resistor in 0402 package with 1% tolerance"
				(at 0 0 0)
				(effects
					(font
						(size 1.27 1.27)
					)
					(hide yes)
				)
			)
			(property "MPN" "CR0402-FX-1002GLF"
				(at 20.32 -20.32 0)
				(effects
					(font
						(size 1.27 1.27)
						(thickness 0.15)
					)
					(justify left bottom)
					(hide yes)
				)
			)
			(property "Manufacturer" "Bourns"
				(at 20.32 -22.86 0)
				(effects
					(font
						(size 1.27 1.27)
						(thickness 0.15)
					)
					(justify left bottom)
					(hide yes)
				)
			)
			(property "License" "Apache-2.0"
				(at 20.32 -25.4 0)
				(effects
					(font
						(size 1.27 1.27)
						(thickness 0.15)
					)
					(justify left bottom)
					(hide yes)
				)
			)
			(property "Author" "Antmicro"
				(at 20.32 -27.94 0)
				(effects
					(font
						(size 1.27 1.27)
						(thickness 0.15)
					)
					(justify left bottom)
					(hide yes)
				)
			)
			(property "Val" "10k"
				(at 20.32 -7.62 0)
				(effects
					(font
						(size 1.27 1.27)
						(thickness 0.15)
					)
					(justify left bottom)
				)
			)
			(property "Tolerance" "1%"
				(at 20.32 -10.16 0)
				(effects
					(font
						(size 1.27 1.27)
					)
					(justify left bottom)
					(hide yes)
				)
			)
			(symbol "R_10k_0402_0_1"
				(rectangle
					(start 0.635 0.889)
					(end 4.445 -0.889)
					(stroke
						(width 0.254)
						(type default)
					)
					(fill
						(type none)
					)
				)
			)
			(symbol "R_10k_0402_1_1"
				(pin passive line
					(at 0 0 0)
					(length 0.635)
					(name "~"
						(effects
							(font
								(size 1.27 1.27)
							)
						)
					)
					(number "1"
						(effects
							(font
								(size 1.27 1.27)
							)
						)
					)
				)
				(pin passive line
					(at 5.08 0 180)
					(length 0.635)
					(name "~"
						(effects
							(font
								(size 1.27 1.27)
							)
						)
					)
					(number "2"
						(effects
							(font
								(size 1.27 1.27)
							)
						)
					)
				)
			)
		)
	(symbol "antmicroResistors0402:R_1k_0402"
			(pin_numbers
				(hide yes)
			)
			(pin_names
				(hide yes)
			)
			(exclude_from_sim no)
			(in_bom yes)
			(on_board yes)
			(property "Reference" "R"
				(at 20.32 -5.08 0)
				(effects
					(font
						(size 1.27 1.27)
						(thickness 0.15)
					)
					(justify left bottom)
				)
			)
			(property "Value" "R_1k_0402"
				(at 20.32 -12.7 0)
				(effects
					(font
						(size 1.27 1.27)
						(thickness 0.15)
					)
					(justify left bottom)
					(hide yes)
				)
			)
			(property "Footprint" "antmicro-footprints:R_0402_1005Metric"
				(at 20.32 -15.24 0)
				(effects
					(font
						(size 1.27 1.27)
						(thickness 0.15)
					)
					(justify left bottom)
					(hide yes)
				)
			)
			(property "Datasheet" "https://www.bourns.com/docs/product-datasheets/cr.pdf"
				(at 20.32 -17.78 0)
				(effects
					(font
						(size 1.27 1.27)
						(thickness 0.15)
					)
					(justify left bottom)
					(hide yes)
				)
			)
			(property "Description" "1k resistor in 0402 package with 1% tolerance"
				(at 0 0 0)
				(effects
					(font
						(size 1.27 1.27)
					)
					(hide yes)
				)
			)
			(property "MPN" "CR0402-FX-1001GLF"
				(at 20.32 -20.32 0)
				(effects
					(font
						(size 1.27 1.27)
						(thickness 0.15)
					)
					(justify left bottom)
					(hide yes)
				)
			)
			(property "Manufacturer" "Bourns"
				(at 20.32 -22.86 0)
				(effects
					(font
						(size 1.27 1.27)
						(thickness 0.15)
					)
					(justify left bottom)
					(hide yes)
				)
			)
			(property "License" "Apache-2.0"
				(at 20.32 -25.4 0)
				(effects
					(font
						(size 1.27 1.27)
						(thickness 0.15)
					)
					(justify left bottom)
					(hide yes)
				)
			)
			(property "Author" "Antmicro"
				(at 20.32 -27.94 0)
				(effects
					(font
						(size 1.27 1.27)
						(thickness 0.15)
					)
					(justify left bottom)
					(hide yes)
				)
			)
			(property "Val" "1k"
				(at 20.32 -7.62 0)
				(effects
					(font
						(size 1.27 1.27)
						(thickness 0.15)
					)
					(justify left bottom)
				)
			)
			(property "Tolerance" "1%"
				(at 20.32 -10.16 0)
				(effects
					(font
						(size 1.27 1.27)
					)
					(justify left bottom)
					(hide yes)
				)
			)
			(symbol "R_1k_0402_0_1"
				(rectangle
					(start 0.635 0.889)
					(end 4.445 -0.889)
					(stroke
						(width 0.254)
						(type default)
					)
					(fill
						(type none)
					)
				)
			)
			(symbol "R_1k_0402_1_1"
				(pin passive line
					(at 0 0 0)
					(length 0.635)
					(name "~"
						(effects
							(font
								(size 1.27 1.27)
							)
						)
					)
					(number "1"
						(effects
							(font
								(size 1.27 1.27)
							)
						)
					)
				)
				(pin passive line
					(at 5.08 0 180)
					(length 0.635)
					(name "~"
						(effects
							(font
								(size 1.27 1.27)
							)
						)
					)
					(number "2"
						(effects
							(font
								(size 1.27 1.27)
							)
						)
					)
				)
			)
		)
	(symbol "antmicroResistors0402:R_220R_0402"
			(pin_numbers
				(hide yes)
			)
			(pin_names
				(hide yes)
			)
			(exclude_from_sim no)
			(in_bom yes)
			(on_board yes)
			(property "Reference" "R"
				(at 20.32 -5.08 0)
				(effects
					(font
						(size 1.27 1.27)
						(thickness 0.15)
					)
					(justify left bottom)
				)
			)
			(property "Value" "R_220R_0402"
				(at 20.32 -12.7 0)
				(effects
					(font
						(size 1.27 1.27)
						(thickness 0.15)
					)
					(justify left bottom)
					(hide yes)
				)
			)
			(property "Footprint" "antmicro-footprints:R_0402_1005Metric"
				(at 20.32 -15.24 0)
				(effects
					(font
						(size 1.27 1.27)
						(thickness 0.15)
					)
					(justify left bottom)
					(hide yes)
				)
			)
			(property "Datasheet" "https://www.bourns.com/docs/product-datasheets/cr.pdf"
				(at 20.32 -17.78 0)
				(effects
					(font
						(size 1.27 1.27)
						(thickness 0.15)
					)
					(justify left bottom)
					(hide yes)
				)
			)
			(property "Description" "220R resistor in 0402 package with 1% tolerance"
				(at 0 0 0)
				(effects
					(font
						(size 1.27 1.27)
					)
					(hide yes)
				)
			)
			(property "MPN" "CR0402-FX-2200GLF"
				(at 20.32 -20.32 0)
				(effects
					(font
						(size 1.27 1.27)
						(thickness 0.15)
					)
					(justify left bottom)
					(hide yes)
				)
			)
			(property "Manufacturer" "Bourns"
				(at 20.32 -22.86 0)
				(effects
					(font
						(size 1.27 1.27)
						(thickness 0.15)
					)
					(justify left bottom)
					(hide yes)
				)
			)
			(property "License" "Apache-2.0"
				(at 20.32 -25.4 0)
				(effects
					(font
						(size 1.27 1.27)
						(thickness 0.15)
					)
					(justify left bottom)
					(hide yes)
				)
			)
			(property "Author" "Antmicro"
				(at 20.32 -27.94 0)
				(effects
					(font
						(size 1.27 1.27)
						(thickness 0.15)
					)
					(justify left bottom)
					(hide yes)
				)
			)
			(property "Val" "220R"
				(at 20.32 -7.62 0)
				(effects
					(font
						(size 1.27 1.27)
						(thickness 0.15)
					)
					(justify left bottom)
				)
			)
			(property "Tolerance" "1%"
				(at 20.32 -10.16 0)
				(effects
					(font
						(size 1.27 1.27)
					)
					(justify left bottom)
					(hide yes)
				)
			)
			(symbol "R_220R_0402_0_1"
				(rectangle
					(start 0.635 0.889)
					(end 4.445 -0.889)
					(stroke
						(width 0.254)
						(type default)
					)
					(fill
						(type none)
					)
				)
			)
			(symbol "R_220R_0402_1_1"
				(pin passive line
					(at 0 0 0)
					(length 0.635)
					(name "~"
						(effects
							(font
								(size 1.27 1.27)
							)
						)
					)
					(number "1"
						(effects
							(font
								(size 1.27 1.27)
							)
						)
					)
				)
				(pin passive line
					(at 5.08 0 180)
					(length 0.635)
					(name "~"
						(effects
							(font
								(size 1.27 1.27)
							)
						)
					)
					(number "2"
						(effects
							(font
								(size 1.27 1.27)
							)
						)
					)
				)
			)
		)
	(symbol "antmicroResistors0402:R_240R_0402"
			(pin_numbers
				(hide yes)
			)
			(pin_names
				(hide yes)
			)
			(exclude_from_sim no)
			(in_bom yes)
			(on_board yes)
			(property "Reference" "R"
				(at 20.32 -5.08 0)
				(effects
					(font
						(size 1.27 1.27)
						(thickness 0.15)
					)
					(justify left bottom)
				)
			)
			(property "Value" "R_240R_0402"
				(at 20.32 -12.7 0)
				(effects
					(font
						(size 1.27 1.27)
						(thickness 0.15)
					)
					(justify left bottom)
					(hide yes)
				)
			)
			(property "Footprint" "antmicro-footprints:R_0402_1005Metric"
				(at 20.32 -15.24 0)
				(effects
					(font
						(size 1.27 1.27)
						(thickness 0.15)
					)
					(justify left bottom)
					(hide yes)
				)
			)
			(property "Datasheet" "https://www.bourns.com/docs/product-datasheets/cr.pdf"
				(at 20.32 -17.78 0)
				(effects
					(font
						(size 1.27 1.27)
						(thickness 0.15)
					)
					(justify left bottom)
					(hide yes)
				)
			)
			(property "Description" "240R resistor in 0402 package with 1% tolerance"
				(at 0 0 0)
				(effects
					(font
						(size 1.27 1.27)
					)
					(hide yes)
				)
			)
			(property "MPN" "CR0402-FX-2400GLF"
				(at 20.32 -20.32 0)
				(effects
					(font
						(size 1.27 1.27)
						(thickness 0.15)
					)
					(justify left bottom)
					(hide yes)
				)
			)
			(property "Manufacturer" "Bourns"
				(at 20.32 -22.86 0)
				(effects
					(font
						(size 1.27 1.27)
						(thickness 0.15)
					)
					(justify left bottom)
					(hide yes)
				)
			)
			(property "License" "Apache-2.0"
				(at 20.32 -25.4 0)
				(effects
					(font
						(size 1.27 1.27)
						(thickness 0.15)
					)
					(justify left bottom)
					(hide yes)
				)
			)
			(property "Author" "Antmicro"
				(at 20.32 -27.94 0)
				(effects
					(font
						(size 1.27 1.27)
						(thickness 0.15)
					)
					(justify left bottom)
					(hide yes)
				)
			)
			(property "Val" "240R"
				(at 20.32 -7.62 0)
				(effects
					(font
						(size 1.27 1.27)
						(thickness 0.15)
					)
					(justify left bottom)
				)
			)
			(property "Tolerance" "1%"
				(at 20.32 -10.16 0)
				(effects
					(font
						(size 1.27 1.27)
					)
					(justify left bottom)
					(hide yes)
				)
			)
			(symbol "R_240R_0402_0_1"
				(rectangle
					(start 0.635 0.889)
					(end 4.445 -0.889)
					(stroke
						(width 0.254)
						(type default)
					)
					(fill
						(type none)
					)
				)
			)
			(symbol "R_240R_0402_1_1"
				(pin passive line
					(at 0 0 0)
					(length 0.635)
					(name "~"
						(effects
							(font
								(size 1.27 1.27)
							)
						)
					)
					(number "1"
						(effects
							(font
								(size 1.27 1.27)
							)
						)
					)
				)
				(pin passive line
					(at 5.08 0 180)
					(length 0.635)
					(name "~"
						(effects
							(font
								(size 1.27 1.27)
							)
						)
					)
					(number "2"
						(effects
							(font
								(size 1.27 1.27)
							)
						)
					)
				)
			)
		)
	(symbol "antmicroTestPoints:TP_1mm_SMD"
			(pin_numbers
				(hide yes)
			)
			(pin_names
				(hide yes)
			)
			(exclude_from_sim no)
			(in_bom yes)
			(on_board yes)
			(property "Reference" "TP"
				(at 15.24 -5.08 0)
				(effects
					(font
						(size 1.27 1.27)
						(thickness 0.15)
					)
					(justify left bottom)
				)
			)
			(property "Value" "TP_1mm_SMD"
				(at 15.24 -7.62 0)
				(effects
					(font
						(size 1.27 1.27)
						(thickness 0.15)
					)
					(justify left bottom)
					(hide yes)
				)
			)
			(property "Footprint" "antmicro-footprints:TP_SMD_1mm"
				(at 15.24 -10.16 0)
				(effects
					(font
						(size 1.27 1.27)
						(thickness 0.15)
					)
					(justify left bottom)
					(hide yes)
				)
			)
			(property "Datasheet" ""
				(at 15.24 -12.7 0)
				(effects
					(font
						(size 1.27 1.27)
						(thickness 0.15)
					)
					(justify left bottom)
					(hide yes)
				)
			)
			(property "Description" "Test Point 1mm"
				(at 0 0 0)
				(effects
					(font
						(size 1.27 1.27)
					)
					(hide yes)
				)
			)
			(property "MPN" ""
				(at 0 0 0)
				(effects
					(font
						(size 1.27 1.27)
					)
					(hide yes)
				)
			)
			(property "Manufacturer" ""
				(at 0 0 0)
				(effects
					(font
						(size 1.27 1.27)
					)
					(hide yes)
				)
			)
			(property "Author" "Antmicro"
				(at 15.24 -15.24 0)
				(effects
					(font
						(size 1.27 1.27)
						(thickness 0.15)
					)
					(justify left bottom)
					(hide yes)
				)
			)
			(property "License" "Apache-2.0"
				(at 15.24 -17.78 0)
				(effects
					(font
						(size 1.27 1.27)
						(thickness 0.15)
					)
					(justify left bottom)
					(hide yes)
				)
			)
			(symbol "TP_1mm_SMD_1_1"
				(circle
					(center 3.175 0)
					(radius 0.635)
					(stroke
						(width 0.254)
						(type default)
					)
					(fill
						(type none)
					)
				)
				(pin passive line
					(at 0 0 0)
					(length 2.54)
					(name "1"
						(effects
							(font
								(size 1.27 1.27)
							)
						)
					)
					(number "1"
						(effects
							(font
								(size 1.27 1.27)
							)
						)
					)
				)
			)
		)
	(symbol "antmicropower:GND"
			(power)
			(pin_names
				(offset 0)
			)
			(exclude_from_sim no)
			(in_bom yes)
			(on_board yes)
			(property "Reference" "#PWR"
				(at 0 -6.35 0)
				(effects
					(font
						(size 1.27 1.27)
					)
					(hide yes)
				)
			)
			(property "Value" "GND"
				(at 0 -3.81 0)
				(effects
					(font
						(size 1.27 1.27)
					)
				)
			)
			(property "Footprint" ""
				(at 0 0 0)
				(effects
					(font
						(size 1.27 1.27)
					)
					(hide yes)
				)
			)
			(property "Datasheet" ""
				(at 0 0 0)
				(effects
					(font
						(size 1.27 1.27)
					)
					(hide yes)
				)
			)
			(property "Description" ""
				(at 0 0 0)
				(effects
					(font
						(size 1.27 1.27)
					)
					(hide yes)
				)
			)
			(symbol "GND_0_1"
				(polyline
					(pts
						(xy 0 0) (xy 0 -1.27) (xy 1.27 -1.27) (xy 0 -2.54) (xy -1.27 -1.27) (xy 0 -1.27)
					)
					(stroke
						(width 0)
						(type default)
					)
					(fill
						(type none)
					)
				)
			)
			(symbol "GND_1_1"
				(pin power_in line
					(at 0 0 270)
					(length 0)
					(hide yes)
					(name "GND"
						(effects
							(font
								(size 1.27 1.27)
							)
						)
					)
					(number "1"
						(effects
							(font
								(size 1.27 1.27)
							)
						)
					)
				)
			)
		)
	(symbol "ddr5-testbed:C_100n_0201_10"
			(pin_numbers
				(hide yes)
			)
			(pin_names
				(hide yes)
			)
			(exclude_from_sim no)
			(in_bom yes)
			(on_board yes)
			(property "Reference" "C"
				(at 20.32 -5.08 0)
				(effects
					(font
						(size 1.27 1.27)
						(thickness 0.15)
					)
					(justify left bottom)
				)
			)
			(property "Value" "C_100n_0201_10"
				(at 20.32 -10.16 0)
				(effects
					(font
						(size 1.27 1.27)
						(thickness 0.15)
					)
					(justify left bottom)
					(hide yes)
				)
			)
			(property "Footprint" "ddr5-testbed-footprints:C_0201"
				(at 20.32 -12.7 0)
				(effects
					(font
						(size 1.27 1.27)
						(thickness 0.15)
					)
					(justify left bottom)
					(hide yes)
				)
			)
			(property "Datasheet" ""
				(at 20.32 -15.24 0)
				(effects
					(font
						(size 1.27 1.27)
						(thickness 0.15)
					)
					(justify left bottom)
					(hide yes)
				)
			)
			(property "Description" ""
				(at 0 0 0)
				(effects
					(font
						(size 1.27 1.27)
					)
					(hide yes)
				)
			)
			(property "MPN" "CC0201KRX6S5BB104"
				(at 20.32 -17.78 0)
				(effects
					(font
						(size 1.27 1.27)
						(thickness 0.15)
					)
					(justify left bottom)
					(hide yes)
				)
			)
			(property "Manufacturer" "Yaego"
				(at 20.32 -20.32 0)
				(effects
					(font
						(size 1.27 1.27)
						(thickness 0.15)
					)
					(justify left bottom)
					(hide yes)
				)
			)
			(property "License" "Apache-2.0"
				(at 20.32 -22.86 0)
				(effects
					(font
						(size 1.27 1.27)
						(thickness 0.15)
					)
					(justify left bottom)
					(hide yes)
				)
			)
			(property "Author" "Antmicro"
				(at 20.32 -25.4 0)
				(effects
					(font
						(size 1.27 1.27)
						(thickness 0.15)
					)
					(justify left bottom)
					(hide yes)
				)
			)
			(property "Val" "100n"
				(at 20.32 -7.62 0)
				(effects
					(font
						(size 1.27 1.27)
						(thickness 0.15)
					)
					(justify left bottom)
				)
			)
			(property "Voltage" ""
				(at 20.32 -27.94 0)
				(effects
					(font
						(size 1.27 1.27)
					)
					(justify left bottom)
					(hide yes)
				)
			)
			(property "Dielectric" ""
				(at 20.32 -30.48 0)
				(effects
					(font
						(size 1.27 1.27)
					)
					(justify left bottom)
					(hide yes)
				)
			)
			(symbol "C_100n_0201_10_0_1"
				(polyline
					(pts
						(xy 2.032 -1.524) (xy 2.032 1.524)
					)
					(stroke
						(width 0.3048)
						(type default)
					)
					(fill
						(type none)
					)
				)
				(polyline
					(pts
						(xy 3.048 -1.524) (xy 3.048 1.524)
					)
					(stroke
						(width 0.3302)
						(type default)
					)
					(fill
						(type none)
					)
				)
			)
			(symbol "C_100n_0201_10_1_1"
				(pin passive line
					(at 0 0 0)
					(length 2.032)
					(name "~"
						(effects
							(font
								(size 1.27 1.27)
							)
						)
					)
					(number "1"
						(effects
							(font
								(size 1.27 1.27)
							)
						)
					)
				)
				(pin passive line
					(at 5.08 0 180)
					(length 2.032)
					(name "~"
						(effects
							(font
								(size 1.27 1.27)
							)
						)
					)
					(number "2"
						(effects
							(font
								(size 1.27 1.27)
							)
						)
					)
				)
			)
		)
	(symbol "ddr5-testbed:C_100n_0201_11"
			(pin_numbers
				(hide yes)
			)
			(pin_names
				(hide yes)
			)
			(exclude_from_sim no)
			(in_bom yes)
			(on_board yes)
			(property "Reference" "C"
				(at 20.32 -5.08 0)
				(effects
					(font
						(size 1.27 1.27)
						(thickness 0.15)
					)
					(justify left bottom)
				)
			)
			(property "Value" "C_100n_0201_11"
				(at 20.32 -10.16 0)
				(effects
					(font
						(size 1.27 1.27)
						(thickness 0.15)
					)
					(justify left bottom)
					(hide yes)
				)
			)
			(property "Footprint" "ddr5-testbed-footprints:C_0201"
				(at 20.32 -12.7 0)
				(effects
					(font
						(size 1.27 1.27)
						(thickness 0.15)
					)
					(justify left bottom)
					(hide yes)
				)
			)
			(property "Datasheet" ""
				(at 20.32 -15.24 0)
				(effects
					(font
						(size 1.27 1.27)
						(thickness 0.15)
					)
					(justify left bottom)
					(hide yes)
				)
			)
			(property "Description" ""
				(at 0 0 0)
				(effects
					(font
						(size 1.27 1.27)
					)
					(hide yes)
				)
			)
			(property "MPN" "CC0201KRX6S5BB104"
				(at 20.32 -17.78 0)
				(effects
					(font
						(size 1.27 1.27)
						(thickness 0.15)
					)
					(justify left bottom)
					(hide yes)
				)
			)
			(property "Manufacturer" "Yaego"
				(at 20.32 -20.32 0)
				(effects
					(font
						(size 1.27 1.27)
						(thickness 0.15)
					)
					(justify left bottom)
					(hide yes)
				)
			)
			(property "License" "Apache-2.0"
				(at 20.32 -22.86 0)
				(effects
					(font
						(size 1.27 1.27)
						(thickness 0.15)
					)
					(justify left bottom)
					(hide yes)
				)
			)
			(property "Author" "Antmicro"
				(at 20.32 -25.4 0)
				(effects
					(font
						(size 1.27 1.27)
						(thickness 0.15)
					)
					(justify left bottom)
					(hide yes)
				)
			)
			(property "Val" "100n"
				(at 20.32 -7.62 0)
				(effects
					(font
						(size 1.27 1.27)
						(thickness 0.15)
					)
					(justify left bottom)
				)
			)
			(property "Voltage" ""
				(at 20.32 -27.94 0)
				(effects
					(font
						(size 1.27 1.27)
					)
					(justify left bottom)
					(hide yes)
				)
			)
			(property "Dielectric" ""
				(at 20.32 -30.48 0)
				(effects
					(font
						(size 1.27 1.27)
					)
					(justify left bottom)
					(hide yes)
				)
			)
			(symbol "C_100n_0201_11_0_1"
				(polyline
					(pts
						(xy 2.032 -1.524) (xy 2.032 1.524)
					)
					(stroke
						(width 0.3048)
						(type default)
					)
					(fill
						(type none)
					)
				)
				(polyline
					(pts
						(xy 3.048 -1.524) (xy 3.048 1.524)
					)
					(stroke
						(width 0.3302)
						(type default)
					)
					(fill
						(type none)
					)
				)
			)
			(symbol "C_100n_0201_11_1_1"
				(pin passive line
					(at 0 0 0)
					(length 2.032)
					(name "~"
						(effects
							(font
								(size 1.27 1.27)
							)
						)
					)
					(number "1"
						(effects
							(font
								(size 1.27 1.27)
							)
						)
					)
				)
				(pin passive line
					(at 5.08 0 180)
					(length 2.032)
					(name "~"
						(effects
							(font
								(size 1.27 1.27)
							)
						)
					)
					(number "2"
						(effects
							(font
								(size 1.27 1.27)
							)
						)
					)
				)
			)
		)
	(symbol "ddr5-testbed:C_100n_0201_12"
			(pin_numbers
				(hide yes)
			)
			(pin_names
				(hide yes)
			)
			(exclude_from_sim no)
			(in_bom yes)
			(on_board yes)
			(property "Reference" "C"
				(at 20.32 -5.08 0)
				(effects
					(font
						(size 1.27 1.27)
						(thickness 0.15)
					)
					(justify left bottom)
				)
			)
			(property "Value" "C_100n_0201_12"
				(at 20.32 -10.16 0)
				(effects
					(font
						(size 1.27 1.27)
						(thickness 0.15)
					)
					(justify left bottom)
					(hide yes)
				)
			)
			(property "Footprint" "ddr5-testbed-footprints:C_0201"
				(at 20.32 -12.7 0)
				(effects
					(font
						(size 1.27 1.27)
						(thickness 0.15)
					)
					(justify left bottom)
					(hide yes)
				)
			)
			(property "Datasheet" ""
				(at 20.32 -15.24 0)
				(effects
					(font
						(size 1.27 1.27)
						(thickness 0.15)
					)
					(justify left bottom)
					(hide yes)
				)
			)
			(property "Description" ""
				(at 0 0 0)
				(effects
					(font
						(size 1.27 1.27)
					)
					(hide yes)
				)
			)
			(property "MPN" "CC0201KRX6S5BB104"
				(at 20.32 -17.78 0)
				(effects
					(font
						(size 1.27 1.27)
						(thickness 0.15)
					)
					(justify left bottom)
					(hide yes)
				)
			)
			(property "Manufacturer" "Yaego"
				(at 20.32 -20.32 0)
				(effects
					(font
						(size 1.27 1.27)
						(thickness 0.15)
					)
					(justify left bottom)
					(hide yes)
				)
			)
			(property "License" "Apache-2.0"
				(at 20.32 -22.86 0)
				(effects
					(font
						(size 1.27 1.27)
						(thickness 0.15)
					)
					(justify left bottom)
					(hide yes)
				)
			)
			(property "Author" "Antmicro"
				(at 20.32 -25.4 0)
				(effects
					(font
						(size 1.27 1.27)
						(thickness 0.15)
					)
					(justify left bottom)
					(hide yes)
				)
			)
			(property "Val" "100n"
				(at 20.32 -7.62 0)
				(effects
					(font
						(size 1.27 1.27)
						(thickness 0.15)
					)
					(justify left bottom)
				)
			)
			(property "Voltage" ""
				(at 20.32 -27.94 0)
				(effects
					(font
						(size 1.27 1.27)
					)
					(justify left bottom)
					(hide yes)
				)
			)
			(property "Dielectric" ""
				(at 20.32 -30.48 0)
				(effects
					(font
						(size 1.27 1.27)
					)
					(justify left bottom)
					(hide yes)
				)
			)
			(symbol "C_100n_0201_12_0_1"
				(polyline
					(pts
						(xy 2.032 -1.524) (xy 2.032 1.524)
					)
					(stroke
						(width 0.3048)
						(type default)
					)
					(fill
						(type none)
					)
				)
				(polyline
					(pts
						(xy 3.048 -1.524) (xy 3.048 1.524)
					)
					(stroke
						(width 0.3302)
						(type default)
					)
					(fill
						(type none)
					)
				)
			)
			(symbol "C_100n_0201_12_1_1"
				(pin passive line
					(at 0 0 0)
					(length 2.032)
					(name "~"
						(effects
							(font
								(size 1.27 1.27)
							)
						)
					)
					(number "1"
						(effects
							(font
								(size 1.27 1.27)
							)
						)
					)
				)
				(pin passive line
					(at 5.08 0 180)
					(length 2.032)
					(name "~"
						(effects
							(font
								(size 1.27 1.27)
							)
						)
					)
					(number "2"
						(effects
							(font
								(size 1.27 1.27)
							)
						)
					)
				)
			)
		)
	(symbol "ddr5-testbed:C_100n_0201_13"
			(pin_numbers
				(hide yes)
			)
			(pin_names
				(hide yes)
			)
			(exclude_from_sim no)
			(in_bom yes)
			(on_board yes)
			(property "Reference" "C"
				(at 20.32 -5.08 0)
				(effects
					(font
						(size 1.27 1.27)
						(thickness 0.15)
					)
					(justify left bottom)
				)
			)
			(property "Value" "C_100n_0201_13"
				(at 20.32 -10.16 0)
				(effects
					(font
						(size 1.27 1.27)
						(thickness 0.15)
					)
					(justify left bottom)
					(hide yes)
				)
			)
			(property "Footprint" "ddr5-testbed-footprints:C_0201"
				(at 20.32 -12.7 0)
				(effects
					(font
						(size 1.27 1.27)
						(thickness 0.15)
					)
					(justify left bottom)
					(hide yes)
				)
			)
			(property "Datasheet" ""
				(at 20.32 -15.24 0)
				(effects
					(font
						(size 1.27 1.27)
						(thickness 0.15)
					)
					(justify left bottom)
					(hide yes)
				)
			)
			(property "Description" ""
				(at 0 0 0)
				(effects
					(font
						(size 1.27 1.27)
					)
					(hide yes)
				)
			)
			(property "MPN" "CC0201KRX6S5BB104"
				(at 20.32 -17.78 0)
				(effects
					(font
						(size 1.27 1.27)
						(thickness 0.15)
					)
					(justify left bottom)
					(hide yes)
				)
			)
			(property "Manufacturer" "Yaego"
				(at 20.32 -20.32 0)
				(effects
					(font
						(size 1.27 1.27)
						(thickness 0.15)
					)
					(justify left bottom)
					(hide yes)
				)
			)
			(property "License" "Apache-2.0"
				(at 20.32 -22.86 0)
				(effects
					(font
						(size 1.27 1.27)
						(thickness 0.15)
					)
					(justify left bottom)
					(hide yes)
				)
			)
			(property "Author" "Antmicro"
				(at 20.32 -25.4 0)
				(effects
					(font
						(size 1.27 1.27)
						(thickness 0.15)
					)
					(justify left bottom)
					(hide yes)
				)
			)
			(property "Val" "100n"
				(at 20.32 -7.62 0)
				(effects
					(font
						(size 1.27 1.27)
						(thickness 0.15)
					)
					(justify left bottom)
				)
			)
			(property "Voltage" ""
				(at 20.32 -27.94 0)
				(effects
					(font
						(size 1.27 1.27)
					)
					(justify left bottom)
					(hide yes)
				)
			)
			(property "Dielectric" ""
				(at 20.32 -30.48 0)
				(effects
					(font
						(size 1.27 1.27)
					)
					(justify left bottom)
					(hide yes)
				)
			)
			(symbol "C_100n_0201_13_0_1"
				(polyline
					(pts
						(xy 2.032 -1.524) (xy 2.032 1.524)
					)
					(stroke
						(width 0.3048)
						(type default)
					)
					(fill
						(type none)
					)
				)
				(polyline
					(pts
						(xy 3.048 -1.524) (xy 3.048 1.524)
					)
					(stroke
						(width 0.3302)
						(type default)
					)
					(fill
						(type none)
					)
				)
			)
			(symbol "C_100n_0201_13_1_1"
				(pin passive line
					(at 0 0 0)
					(length 2.032)
					(name "~"
						(effects
							(font
								(size 1.27 1.27)
							)
						)
					)
					(number "1"
						(effects
							(font
								(size 1.27 1.27)
							)
						)
					)
				)
				(pin passive line
					(at 5.08 0 180)
					(length 2.032)
					(name "~"
						(effects
							(font
								(size 1.27 1.27)
							)
						)
					)
					(number "2"
						(effects
							(font
								(size 1.27 1.27)
							)
						)
					)
				)
			)
		)
	(symbol "ddr5-testbed:C_100n_0201_14"
			(pin_numbers
				(hide yes)
			)
			(pin_names
				(hide yes)
			)
			(exclude_from_sim no)
			(in_bom yes)
			(on_board yes)
			(property "Reference" "C"
				(at 20.32 -5.08 0)
				(effects
					(font
						(size 1.27 1.27)
						(thickness 0.15)
					)
					(justify left bottom)
				)
			)
			(property "Value" "C_100n_0201_14"
				(at 20.32 -10.16 0)
				(effects
					(font
						(size 1.27 1.27)
						(thickness 0.15)
					)
					(justify left bottom)
					(hide yes)
				)
			)
			(property "Footprint" "ddr5-testbed-footprints:C_0201"
				(at 20.32 -12.7 0)
				(effects
					(font
						(size 1.27 1.27)
						(thickness 0.15)
					)
					(justify left bottom)
					(hide yes)
				)
			)
			(property "Datasheet" ""
				(at 20.32 -15.24 0)
				(effects
					(font
						(size 1.27 1.27)
						(thickness 0.15)
					)
					(justify left bottom)
					(hide yes)
				)
			)
			(property "Description" ""
				(at 0 0 0)
				(effects
					(font
						(size 1.27 1.27)
					)
					(hide yes)
				)
			)
			(property "MPN" "CC0201KRX6S5BB104"
				(at 20.32 -17.78 0)
				(effects
					(font
						(size 1.27 1.27)
						(thickness 0.15)
					)
					(justify left bottom)
					(hide yes)
				)
			)
			(property "Manufacturer" "Yaego"
				(at 20.32 -20.32 0)
				(effects
					(font
						(size 1.27 1.27)
						(thickness 0.15)
					)
					(justify left bottom)
					(hide yes)
				)
			)
			(property "License" "Apache-2.0"
				(at 20.32 -22.86 0)
				(effects
					(font
						(size 1.27 1.27)
						(thickness 0.15)
					)
					(justify left bottom)
					(hide yes)
				)
			)
			(property "Author" "Antmicro"
				(at 20.32 -25.4 0)
				(effects
					(font
						(size 1.27 1.27)
						(thickness 0.15)
					)
					(justify left bottom)
					(hide yes)
				)
			)
			(property "Val" "100n"
				(at 20.32 -7.62 0)
				(effects
					(font
						(size 1.27 1.27)
						(thickness 0.15)
					)
					(justify left bottom)
				)
			)
			(property "Voltage" ""
				(at 20.32 -27.94 0)
				(effects
					(font
						(size 1.27 1.27)
					)
					(justify left bottom)
					(hide yes)
				)
			)
			(property "Dielectric" ""
				(at 20.32 -30.48 0)
				(effects
					(font
						(size 1.27 1.27)
					)
					(justify left bottom)
					(hide yes)
				)
			)
			(symbol "C_100n_0201_14_0_1"
				(polyline
					(pts
						(xy 2.032 -1.524) (xy 2.032 1.524)
					)
					(stroke
						(width 0.3048)
						(type default)
					)
					(fill
						(type none)
					)
				)
				(polyline
					(pts
						(xy 3.048 -1.524) (xy 3.048 1.524)
					)
					(stroke
						(width 0.3302)
						(type default)
					)
					(fill
						(type none)
					)
				)
			)
			(symbol "C_100n_0201_14_1_1"
				(pin passive line
					(at 0 0 0)
					(length 2.032)
					(name "~"
						(effects
							(font
								(size 1.27 1.27)
							)
						)
					)
					(number "1"
						(effects
							(font
								(size 1.27 1.27)
							)
						)
					)
				)
				(pin passive line
					(at 5.08 0 180)
					(length 2.032)
					(name "~"
						(effects
							(font
								(size 1.27 1.27)
							)
						)
					)
					(number "2"
						(effects
							(font
								(size 1.27 1.27)
							)
						)
					)
				)
			)
		)
	(symbol "ddr5-testbed:C_100n_0201_15"
			(pin_numbers
				(hide yes)
			)
			(pin_names
				(hide yes)
			)
			(exclude_from_sim no)
			(in_bom yes)
			(on_board yes)
			(property "Reference" "C"
				(at 20.32 -5.08 0)
				(effects
					(font
						(size 1.27 1.27)
						(thickness 0.15)
					)
					(justify left bottom)
				)
			)
			(property "Value" "C_100n_0201_15"
				(at 20.32 -10.16 0)
				(effects
					(font
						(size 1.27 1.27)
						(thickness 0.15)
					)
					(justify left bottom)
					(hide yes)
				)
			)
			(property "Footprint" "ddr5-testbed-footprints:C_0201"
				(at 20.32 -12.7 0)
				(effects
					(font
						(size 1.27 1.27)
						(thickness 0.15)
					)
					(justify left bottom)
					(hide yes)
				)
			)
			(property "Datasheet" ""
				(at 20.32 -15.24 0)
				(effects
					(font
						(size 1.27 1.27)
						(thickness 0.15)
					)
					(justify left bottom)
					(hide yes)
				)
			)
			(property "Description" ""
				(at 0 0 0)
				(effects
					(font
						(size 1.27 1.27)
					)
					(hide yes)
				)
			)
			(property "MPN" "CC0201KRX6S5BB104"
				(at 20.32 -17.78 0)
				(effects
					(font
						(size 1.27 1.27)
						(thickness 0.15)
					)
					(justify left bottom)
					(hide yes)
				)
			)
			(property "Manufacturer" "Yaego"
				(at 20.32 -20.32 0)
				(effects
					(font
						(size 1.27 1.27)
						(thickness 0.15)
					)
					(justify left bottom)
					(hide yes)
				)
			)
			(property "License" "Apache-2.0"
				(at 20.32 -22.86 0)
				(effects
					(font
						(size 1.27 1.27)
						(thickness 0.15)
					)
					(justify left bottom)
					(hide yes)
				)
			)
			(property "Author" "Antmicro"
				(at 20.32 -25.4 0)
				(effects
					(font
						(size 1.27 1.27)
						(thickness 0.15)
					)
					(justify left bottom)
					(hide yes)
				)
			)
			(property "Val" "100n"
				(at 20.32 -7.62 0)
				(effects
					(font
						(size 1.27 1.27)
						(thickness 0.15)
					)
					(justify left bottom)
				)
			)
			(property "Voltage" ""
				(at 20.32 -27.94 0)
				(effects
					(font
						(size 1.27 1.27)
					)
					(justify left bottom)
					(hide yes)
				)
			)
			(property "Dielectric" ""
				(at 20.32 -30.48 0)
				(effects
					(font
						(size 1.27 1.27)
					)
					(justify left bottom)
					(hide yes)
				)
			)
			(symbol "C_100n_0201_15_0_1"
				(polyline
					(pts
						(xy 2.032 -1.524) (xy 2.032 1.524)
					)
					(stroke
						(width 0.3048)
						(type default)
					)
					(fill
						(type none)
					)
				)
				(polyline
					(pts
						(xy 3.048 -1.524) (xy 3.048 1.524)
					)
					(stroke
						(width 0.3302)
						(type default)
					)
					(fill
						(type none)
					)
				)
			)
			(symbol "C_100n_0201_15_1_1"
				(pin passive line
					(at 0 0 0)
					(length 2.032)
					(name "~"
						(effects
							(font
								(size 1.27 1.27)
							)
						)
					)
					(number "1"
						(effects
							(font
								(size 1.27 1.27)
							)
						)
					)
				)
				(pin passive line
					(at 5.08 0 180)
					(length 2.032)
					(name "~"
						(effects
							(font
								(size 1.27 1.27)
							)
						)
					)
					(number "2"
						(effects
							(font
								(size 1.27 1.27)
							)
						)
					)
				)
			)
		)
	(symbol "ddr5-testbed:C_100n_0201_16"
			(pin_numbers
				(hide yes)
			)
			(pin_names
				(hide yes)
			)
			(exclude_from_sim no)
			(in_bom yes)
			(on_board yes)
			(property "Reference" "C"
				(at 20.32 -5.08 0)
				(effects
					(font
						(size 1.27 1.27)
						(thickness 0.15)
					)
					(justify left bottom)
				)
			)
			(property "Value" "C_100n_0201_16"
				(at 20.32 -10.16 0)
				(effects
					(font
						(size 1.27 1.27)
						(thickness 0.15)
					)
					(justify left bottom)
					(hide yes)
				)
			)
			(property "Footprint" "ddr5-testbed-footprints:C_0201"
				(at 20.32 -12.7 0)
				(effects
					(font
						(size 1.27 1.27)
						(thickness 0.15)
					)
					(justify left bottom)
					(hide yes)
				)
			)
			(property "Datasheet" ""
				(at 20.32 -15.24 0)
				(effects
					(font
						(size 1.27 1.27)
						(thickness 0.15)
					)
					(justify left bottom)
					(hide yes)
				)
			)
			(property "Description" ""
				(at 0 0 0)
				(effects
					(font
						(size 1.27 1.27)
					)
					(hide yes)
				)
			)
			(property "MPN" "CC0201KRX6S5BB104"
				(at 20.32 -17.78 0)
				(effects
					(font
						(size 1.27 1.27)
						(thickness 0.15)
					)
					(justify left bottom)
					(hide yes)
				)
			)
			(property "Manufacturer" "Yaego"
				(at 20.32 -20.32 0)
				(effects
					(font
						(size 1.27 1.27)
						(thickness 0.15)
					)
					(justify left bottom)
					(hide yes)
				)
			)
			(property "License" "Apache-2.0"
				(at 20.32 -22.86 0)
				(effects
					(font
						(size 1.27 1.27)
						(thickness 0.15)
					)
					(justify left bottom)
					(hide yes)
				)
			)
			(property "Author" "Antmicro"
				(at 20.32 -25.4 0)
				(effects
					(font
						(size 1.27 1.27)
						(thickness 0.15)
					)
					(justify left bottom)
					(hide yes)
				)
			)
			(property "Val" "100n"
				(at 20.32 -7.62 0)
				(effects
					(font
						(size 1.27 1.27)
						(thickness 0.15)
					)
					(justify left bottom)
				)
			)
			(property "Voltage" ""
				(at 20.32 -27.94 0)
				(effects
					(font
						(size 1.27 1.27)
					)
					(justify left bottom)
					(hide yes)
				)
			)
			(property "Dielectric" ""
				(at 20.32 -30.48 0)
				(effects
					(font
						(size 1.27 1.27)
					)
					(justify left bottom)
					(hide yes)
				)
			)
			(symbol "C_100n_0201_16_0_1"
				(polyline
					(pts
						(xy 2.032 -1.524) (xy 2.032 1.524)
					)
					(stroke
						(width 0.3048)
						(type default)
					)
					(fill
						(type none)
					)
				)
				(polyline
					(pts
						(xy 3.048 -1.524) (xy 3.048 1.524)
					)
					(stroke
						(width 0.3302)
						(type default)
					)
					(fill
						(type none)
					)
				)
			)
			(symbol "C_100n_0201_16_1_1"
				(pin passive line
					(at 0 0 0)
					(length 2.032)
					(name "~"
						(effects
							(font
								(size 1.27 1.27)
							)
						)
					)
					(number "1"
						(effects
							(font
								(size 1.27 1.27)
							)
						)
					)
				)
				(pin passive line
					(at 5.08 0 180)
					(length 2.032)
					(name "~"
						(effects
							(font
								(size 1.27 1.27)
							)
						)
					)
					(number "2"
						(effects
							(font
								(size 1.27 1.27)
							)
						)
					)
				)
			)
		)
	(symbol "ddr5-testbed:C_100n_0201_17"
			(pin_numbers
				(hide yes)
			)
			(pin_names
				(hide yes)
			)
			(exclude_from_sim no)
			(in_bom yes)
			(on_board yes)
			(property "Reference" "C"
				(at 20.32 -5.08 0)
				(effects
					(font
						(size 1.27 1.27)
						(thickness 0.15)
					)
					(justify left bottom)
				)
			)
			(property "Value" "C_100n_0201_17"
				(at 20.32 -10.16 0)
				(effects
					(font
						(size 1.27 1.27)
						(thickness 0.15)
					)
					(justify left bottom)
					(hide yes)
				)
			)
			(property "Footprint" "ddr5-testbed-footprints:C_0201"
				(at 20.32 -12.7 0)
				(effects
					(font
						(size 1.27 1.27)
						(thickness 0.15)
					)
					(justify left bottom)
					(hide yes)
				)
			)
			(property "Datasheet" ""
				(at 20.32 -15.24 0)
				(effects
					(font
						(size 1.27 1.27)
						(thickness 0.15)
					)
					(justify left bottom)
					(hide yes)
				)
			)
			(property "Description" ""
				(at 0 0 0)
				(effects
					(font
						(size 1.27 1.27)
					)
					(hide yes)
				)
			)
			(property "MPN" "CC0201KRX6S5BB104"
				(at 20.32 -17.78 0)
				(effects
					(font
						(size 1.27 1.27)
						(thickness 0.15)
					)
					(justify left bottom)
					(hide yes)
				)
			)
			(property "Manufacturer" "Yaego"
				(at 20.32 -20.32 0)
				(effects
					(font
						(size 1.27 1.27)
						(thickness 0.15)
					)
					(justify left bottom)
					(hide yes)
				)
			)
			(property "License" "Apache-2.0"
				(at 20.32 -22.86 0)
				(effects
					(font
						(size 1.27 1.27)
						(thickness 0.15)
					)
					(justify left bottom)
					(hide yes)
				)
			)
			(property "Author" "Antmicro"
				(at 20.32 -25.4 0)
				(effects
					(font
						(size 1.27 1.27)
						(thickness 0.15)
					)
					(justify left bottom)
					(hide yes)
				)
			)
			(property "Val" "100n"
				(at 20.32 -7.62 0)
				(effects
					(font
						(size 1.27 1.27)
						(thickness 0.15)
					)
					(justify left bottom)
				)
			)
			(property "Voltage" ""
				(at 20.32 -27.94 0)
				(effects
					(font
						(size 1.27 1.27)
					)
					(justify left bottom)
					(hide yes)
				)
			)
			(property "Dielectric" ""
				(at 20.32 -30.48 0)
				(effects
					(font
						(size 1.27 1.27)
					)
					(justify left bottom)
					(hide yes)
				)
			)
			(symbol "C_100n_0201_17_0_1"
				(polyline
					(pts
						(xy 2.032 -1.524) (xy 2.032 1.524)
					)
					(stroke
						(width 0.3048)
						(type default)
					)
					(fill
						(type none)
					)
				)
				(polyline
					(pts
						(xy 3.048 -1.524) (xy 3.048 1.524)
					)
					(stroke
						(width 0.3302)
						(type default)
					)
					(fill
						(type none)
					)
				)
			)
			(symbol "C_100n_0201_17_1_1"
				(pin passive line
					(at 0 0 0)
					(length 2.032)
					(name "~"
						(effects
							(font
								(size 1.27 1.27)
							)
						)
					)
					(number "1"
						(effects
							(font
								(size 1.27 1.27)
							)
						)
					)
				)
				(pin passive line
					(at 5.08 0 180)
					(length 2.032)
					(name "~"
						(effects
							(font
								(size 1.27 1.27)
							)
						)
					)
					(number "2"
						(effects
							(font
								(size 1.27 1.27)
							)
						)
					)
				)
			)
		)
	(symbol "ddr5-testbed:C_100n_0201_18"
			(pin_numbers
				(hide yes)
			)
			(pin_names
				(hide yes)
			)
			(exclude_from_sim no)
			(in_bom yes)
			(on_board yes)
			(property "Reference" "C"
				(at 20.32 -5.08 0)
				(effects
					(font
						(size 1.27 1.27)
						(thickness 0.15)
					)
					(justify left bottom)
				)
			)
			(property "Value" "C_100n_0201_18"
				(at 20.32 -10.16 0)
				(effects
					(font
						(size 1.27 1.27)
						(thickness 0.15)
					)
					(justify left bottom)
					(hide yes)
				)
			)
			(property "Footprint" "ddr5-testbed-footprints:C_0201"
				(at 20.32 -12.7 0)
				(effects
					(font
						(size 1.27 1.27)
						(thickness 0.15)
					)
					(justify left bottom)
					(hide yes)
				)
			)
			(property "Datasheet" ""
				(at 20.32 -15.24 0)
				(effects
					(font
						(size 1.27 1.27)
						(thickness 0.15)
					)
					(justify left bottom)
					(hide yes)
				)
			)
			(property "Description" ""
				(at 0 0 0)
				(effects
					(font
						(size 1.27 1.27)
					)
					(hide yes)
				)
			)
			(property "MPN" "CC0201KRX6S5BB104"
				(at 20.32 -17.78 0)
				(effects
					(font
						(size 1.27 1.27)
						(thickness 0.15)
					)
					(justify left bottom)
					(hide yes)
				)
			)
			(property "Manufacturer" "Yaego"
				(at 20.32 -20.32 0)
				(effects
					(font
						(size 1.27 1.27)
						(thickness 0.15)
					)
					(justify left bottom)
					(hide yes)
				)
			)
			(property "License" "Apache-2.0"
				(at 20.32 -22.86 0)
				(effects
					(font
						(size 1.27 1.27)
						(thickness 0.15)
					)
					(justify left bottom)
					(hide yes)
				)
			)
			(property "Author" "Antmicro"
				(at 20.32 -25.4 0)
				(effects
					(font
						(size 1.27 1.27)
						(thickness 0.15)
					)
					(justify left bottom)
					(hide yes)
				)
			)
			(property "Val" "100n"
				(at 20.32 -7.62 0)
				(effects
					(font
						(size 1.27 1.27)
						(thickness 0.15)
					)
					(justify left bottom)
				)
			)
			(property "Voltage" ""
				(at 20.32 -27.94 0)
				(effects
					(font
						(size 1.27 1.27)
					)
					(justify left bottom)
					(hide yes)
				)
			)
			(property "Dielectric" ""
				(at 20.32 -30.48 0)
				(effects
					(font
						(size 1.27 1.27)
					)
					(justify left bottom)
					(hide yes)
				)
			)
			(symbol "C_100n_0201_18_0_1"
				(polyline
					(pts
						(xy 2.032 -1.524) (xy 2.032 1.524)
					)
					(stroke
						(width 0.3048)
						(type default)
					)
					(fill
						(type none)
					)
				)
				(polyline
					(pts
						(xy 3.048 -1.524) (xy 3.048 1.524)
					)
					(stroke
						(width 0.3302)
						(type default)
					)
					(fill
						(type none)
					)
				)
			)
			(symbol "C_100n_0201_18_1_1"
				(pin passive line
					(at 0 0 0)
					(length 2.032)
					(name "~"
						(effects
							(font
								(size 1.27 1.27)
							)
						)
					)
					(number "1"
						(effects
							(font
								(size 1.27 1.27)
							)
						)
					)
				)
				(pin passive line
					(at 5.08 0 180)
					(length 2.032)
					(name "~"
						(effects
							(font
								(size 1.27 1.27)
							)
						)
					)
					(number "2"
						(effects
							(font
								(size 1.27 1.27)
							)
						)
					)
				)
			)
		)
	(symbol "ddr5-testbed:C_100n_0201_19"
			(pin_numbers
				(hide yes)
			)
			(pin_names
				(hide yes)
			)
			(exclude_from_sim no)
			(in_bom yes)
			(on_board yes)
			(property "Reference" "C"
				(at 20.32 -5.08 0)
				(effects
					(font
						(size 1.27 1.27)
						(thickness 0.15)
					)
					(justify left bottom)
				)
			)
			(property "Value" "C_100n_0201_19"
				(at 20.32 -10.16 0)
				(effects
					(font
						(size 1.27 1.27)
						(thickness 0.15)
					)
					(justify left bottom)
					(hide yes)
				)
			)
			(property "Footprint" "ddr5-testbed-footprints:C_0201"
				(at 20.32 -12.7 0)
				(effects
					(font
						(size 1.27 1.27)
						(thickness 0.15)
					)
					(justify left bottom)
					(hide yes)
				)
			)
			(property "Datasheet" ""
				(at 20.32 -15.24 0)
				(effects
					(font
						(size 1.27 1.27)
						(thickness 0.15)
					)
					(justify left bottom)
					(hide yes)
				)
			)
			(property "Description" ""
				(at 0 0 0)
				(effects
					(font
						(size 1.27 1.27)
					)
					(hide yes)
				)
			)
			(property "MPN" "CC0201KRX6S5BB104"
				(at 20.32 -17.78 0)
				(effects
					(font
						(size 1.27 1.27)
						(thickness 0.15)
					)
					(justify left bottom)
					(hide yes)
				)
			)
			(property "Manufacturer" "Yaego"
				(at 20.32 -20.32 0)
				(effects
					(font
						(size 1.27 1.27)
						(thickness 0.15)
					)
					(justify left bottom)
					(hide yes)
				)
			)
			(property "License" "Apache-2.0"
				(at 20.32 -22.86 0)
				(effects
					(font
						(size 1.27 1.27)
						(thickness 0.15)
					)
					(justify left bottom)
					(hide yes)
				)
			)
			(property "Author" "Antmicro"
				(at 20.32 -25.4 0)
				(effects
					(font
						(size 1.27 1.27)
						(thickness 0.15)
					)
					(justify left bottom)
					(hide yes)
				)
			)
			(property "Val" "100n"
				(at 20.32 -7.62 0)
				(effects
					(font
						(size 1.27 1.27)
						(thickness 0.15)
					)
					(justify left bottom)
				)
			)
			(property "Voltage" ""
				(at 20.32 -27.94 0)
				(effects
					(font
						(size 1.27 1.27)
					)
					(justify left bottom)
					(hide yes)
				)
			)
			(property "Dielectric" ""
				(at 20.32 -30.48 0)
				(effects
					(font
						(size 1.27 1.27)
					)
					(justify left bottom)
					(hide yes)
				)
			)
			(symbol "C_100n_0201_19_0_1"
				(polyline
					(pts
						(xy 2.032 -1.524) (xy 2.032 1.524)
					)
					(stroke
						(width 0.3048)
						(type default)
					)
					(fill
						(type none)
					)
				)
				(polyline
					(pts
						(xy 3.048 -1.524) (xy 3.048 1.524)
					)
					(stroke
						(width 0.3302)
						(type default)
					)
					(fill
						(type none)
					)
				)
			)
			(symbol "C_100n_0201_19_1_1"
				(pin passive line
					(at 0 0 0)
					(length 2.032)
					(name "~"
						(effects
							(font
								(size 1.27 1.27)
							)
						)
					)
					(number "1"
						(effects
							(font
								(size 1.27 1.27)
							)
						)
					)
				)
				(pin passive line
					(at 5.08 0 180)
					(length 2.032)
					(name "~"
						(effects
							(font
								(size 1.27 1.27)
							)
						)
					)
					(number "2"
						(effects
							(font
								(size 1.27 1.27)
							)
						)
					)
				)
			)
		)
	(symbol "ddr5-testbed:C_100n_0201_20"
			(pin_numbers
				(hide yes)
			)
			(pin_names
				(hide yes)
			)
			(exclude_from_sim no)
			(in_bom yes)
			(on_board yes)
			(property "Reference" "C"
				(at 20.32 -5.08 0)
				(effects
					(font
						(size 1.27 1.27)
						(thickness 0.15)
					)
					(justify left bottom)
				)
			)
			(property "Value" "C_100n_0201_20"
				(at 20.32 -10.16 0)
				(effects
					(font
						(size 1.27 1.27)
						(thickness 0.15)
					)
					(justify left bottom)
					(hide yes)
				)
			)
			(property "Footprint" "ddr5-testbed-footprints:C_0201"
				(at 20.32 -12.7 0)
				(effects
					(font
						(size 1.27 1.27)
						(thickness 0.15)
					)
					(justify left bottom)
					(hide yes)
				)
			)
			(property "Datasheet" ""
				(at 20.32 -15.24 0)
				(effects
					(font
						(size 1.27 1.27)
						(thickness 0.15)
					)
					(justify left bottom)
					(hide yes)
				)
			)
			(property "Description" ""
				(at 0 0 0)
				(effects
					(font
						(size 1.27 1.27)
					)
					(hide yes)
				)
			)
			(property "MPN" "CC0201KRX6S5BB104"
				(at 20.32 -17.78 0)
				(effects
					(font
						(size 1.27 1.27)
						(thickness 0.15)
					)
					(justify left bottom)
					(hide yes)
				)
			)
			(property "Manufacturer" "Yaego"
				(at 20.32 -20.32 0)
				(effects
					(font
						(size 1.27 1.27)
						(thickness 0.15)
					)
					(justify left bottom)
					(hide yes)
				)
			)
			(property "License" "Apache-2.0"
				(at 20.32 -22.86 0)
				(effects
					(font
						(size 1.27 1.27)
						(thickness 0.15)
					)
					(justify left bottom)
					(hide yes)
				)
			)
			(property "Author" "Antmicro"
				(at 20.32 -25.4 0)
				(effects
					(font
						(size 1.27 1.27)
						(thickness 0.15)
					)
					(justify left bottom)
					(hide yes)
				)
			)
			(property "Val" "100n"
				(at 20.32 -7.62 0)
				(effects
					(font
						(size 1.27 1.27)
						(thickness 0.15)
					)
					(justify left bottom)
				)
			)
			(property "Voltage" ""
				(at 20.32 -27.94 0)
				(effects
					(font
						(size 1.27 1.27)
					)
					(justify left bottom)
					(hide yes)
				)
			)
			(property "Dielectric" ""
				(at 20.32 -30.48 0)
				(effects
					(font
						(size 1.27 1.27)
					)
					(justify left bottom)
					(hide yes)
				)
			)
			(symbol "C_100n_0201_20_0_1"
				(polyline
					(pts
						(xy 2.032 -1.524) (xy 2.032 1.524)
					)
					(stroke
						(width 0.3048)
						(type default)
					)
					(fill
						(type none)
					)
				)
				(polyline
					(pts
						(xy 3.048 -1.524) (xy 3.048 1.524)
					)
					(stroke
						(width 0.3302)
						(type default)
					)
					(fill
						(type none)
					)
				)
			)
			(symbol "C_100n_0201_20_1_1"
				(pin passive line
					(at 0 0 0)
					(length 2.032)
					(name "~"
						(effects
							(font
								(size 1.27 1.27)
							)
						)
					)
					(number "1"
						(effects
							(font
								(size 1.27 1.27)
							)
						)
					)
				)
				(pin passive line
					(at 5.08 0 180)
					(length 2.032)
					(name "~"
						(effects
							(font
								(size 1.27 1.27)
							)
						)
					)
					(number "2"
						(effects
							(font
								(size 1.27 1.27)
							)
						)
					)
				)
			)
		)
	(symbol "ddr5-testbed:C_100n_0201_21"
			(pin_numbers
				(hide yes)
			)
			(pin_names
				(hide yes)
			)
			(exclude_from_sim no)
			(in_bom yes)
			(on_board yes)
			(property "Reference" "C"
				(at 20.32 -5.08 0)
				(effects
					(font
						(size 1.27 1.27)
						(thickness 0.15)
					)
					(justify left bottom)
				)
			)
			(property "Value" "C_100n_0201_21"
				(at 20.32 -10.16 0)
				(effects
					(font
						(size 1.27 1.27)
						(thickness 0.15)
					)
					(justify left bottom)
					(hide yes)
				)
			)
			(property "Footprint" "ddr5-testbed-footprints:C_0201"
				(at 20.32 -12.7 0)
				(effects
					(font
						(size 1.27 1.27)
						(thickness 0.15)
					)
					(justify left bottom)
					(hide yes)
				)
			)
			(property "Datasheet" ""
				(at 20.32 -15.24 0)
				(effects
					(font
						(size 1.27 1.27)
						(thickness 0.15)
					)
					(justify left bottom)
					(hide yes)
				)
			)
			(property "Description" ""
				(at 0 0 0)
				(effects
					(font
						(size 1.27 1.27)
					)
					(hide yes)
				)
			)
			(property "MPN" "CC0201KRX6S5BB104"
				(at 20.32 -17.78 0)
				(effects
					(font
						(size 1.27 1.27)
						(thickness 0.15)
					)
					(justify left bottom)
					(hide yes)
				)
			)
			(property "Manufacturer" "Yaego"
				(at 20.32 -20.32 0)
				(effects
					(font
						(size 1.27 1.27)
						(thickness 0.15)
					)
					(justify left bottom)
					(hide yes)
				)
			)
			(property "License" "Apache-2.0"
				(at 20.32 -22.86 0)
				(effects
					(font
						(size 1.27 1.27)
						(thickness 0.15)
					)
					(justify left bottom)
					(hide yes)
				)
			)
			(property "Author" "Antmicro"
				(at 20.32 -25.4 0)
				(effects
					(font
						(size 1.27 1.27)
						(thickness 0.15)
					)
					(justify left bottom)
					(hide yes)
				)
			)
			(property "Val" "100n"
				(at 20.32 -7.62 0)
				(effects
					(font
						(size 1.27 1.27)
						(thickness 0.15)
					)
					(justify left bottom)
				)
			)
			(property "Voltage" ""
				(at 20.32 -27.94 0)
				(effects
					(font
						(size 1.27 1.27)
					)
					(justify left bottom)
					(hide yes)
				)
			)
			(property "Dielectric" ""
				(at 20.32 -30.48 0)
				(effects
					(font
						(size 1.27 1.27)
					)
					(justify left bottom)
					(hide yes)
				)
			)
			(symbol "C_100n_0201_21_0_1"
				(polyline
					(pts
						(xy 2.032 -1.524) (xy 2.032 1.524)
					)
					(stroke
						(width 0.3048)
						(type default)
					)
					(fill
						(type none)
					)
				)
				(polyline
					(pts
						(xy 3.048 -1.524) (xy 3.048 1.524)
					)
					(stroke
						(width 0.3302)
						(type default)
					)
					(fill
						(type none)
					)
				)
			)
			(symbol "C_100n_0201_21_1_1"
				(pin passive line
					(at 0 0 0)
					(length 2.032)
					(name "~"
						(effects
							(font
								(size 1.27 1.27)
							)
						)
					)
					(number "1"
						(effects
							(font
								(size 1.27 1.27)
							)
						)
					)
				)
				(pin passive line
					(at 5.08 0 180)
					(length 2.032)
					(name "~"
						(effects
							(font
								(size 1.27 1.27)
							)
						)
					)
					(number "2"
						(effects
							(font
								(size 1.27 1.27)
							)
						)
					)
				)
			)
		)
	(symbol "ddr5-testbed:C_100n_0201_22"
			(pin_numbers
				(hide yes)
			)
			(pin_names
				(hide yes)
			)
			(exclude_from_sim no)
			(in_bom yes)
			(on_board yes)
			(property "Reference" "C"
				(at 20.32 -5.08 0)
				(effects
					(font
						(size 1.27 1.27)
						(thickness 0.15)
					)
					(justify left bottom)
				)
			)
			(property "Value" "C_100n_0201_22"
				(at 20.32 -10.16 0)
				(effects
					(font
						(size 1.27 1.27)
						(thickness 0.15)
					)
					(justify left bottom)
					(hide yes)
				)
			)
			(property "Footprint" "ddr5-testbed-footprints:C_0201"
				(at 20.32 -12.7 0)
				(effects
					(font
						(size 1.27 1.27)
						(thickness 0.15)
					)
					(justify left bottom)
					(hide yes)
				)
			)
			(property "Datasheet" ""
				(at 20.32 -15.24 0)
				(effects
					(font
						(size 1.27 1.27)
						(thickness 0.15)
					)
					(justify left bottom)
					(hide yes)
				)
			)
			(property "Description" ""
				(at 0 0 0)
				(effects
					(font
						(size 1.27 1.27)
					)
					(hide yes)
				)
			)
			(property "MPN" "CC0201KRX6S5BB104"
				(at 20.32 -17.78 0)
				(effects
					(font
						(size 1.27 1.27)
						(thickness 0.15)
					)
					(justify left bottom)
					(hide yes)
				)
			)
			(property "Manufacturer" "Yaego"
				(at 20.32 -20.32 0)
				(effects
					(font
						(size 1.27 1.27)
						(thickness 0.15)
					)
					(justify left bottom)
					(hide yes)
				)
			)
			(property "License" "Apache-2.0"
				(at 20.32 -22.86 0)
				(effects
					(font
						(size 1.27 1.27)
						(thickness 0.15)
					)
					(justify left bottom)
					(hide yes)
				)
			)
			(property "Author" "Antmicro"
				(at 20.32 -25.4 0)
				(effects
					(font
						(size 1.27 1.27)
						(thickness 0.15)
					)
					(justify left bottom)
					(hide yes)
				)
			)
			(property "Val" "100n"
				(at 20.32 -7.62 0)
				(effects
					(font
						(size 1.27 1.27)
						(thickness 0.15)
					)
					(justify left bottom)
				)
			)
			(property "Voltage" ""
				(at 20.32 -27.94 0)
				(effects
					(font
						(size 1.27 1.27)
					)
					(justify left bottom)
					(hide yes)
				)
			)
			(property "Dielectric" ""
				(at 20.32 -30.48 0)
				(effects
					(font
						(size 1.27 1.27)
					)
					(justify left bottom)
					(hide yes)
				)
			)
			(symbol "C_100n_0201_22_0_1"
				(polyline
					(pts
						(xy 2.032 -1.524) (xy 2.032 1.524)
					)
					(stroke
						(width 0.3048)
						(type default)
					)
					(fill
						(type none)
					)
				)
				(polyline
					(pts
						(xy 3.048 -1.524) (xy 3.048 1.524)
					)
					(stroke
						(width 0.3302)
						(type default)
					)
					(fill
						(type none)
					)
				)
			)
			(symbol "C_100n_0201_22_1_1"
				(pin passive line
					(at 0 0 0)
					(length 2.032)
					(name "~"
						(effects
							(font
								(size 1.27 1.27)
							)
						)
					)
					(number "1"
						(effects
							(font
								(size 1.27 1.27)
							)
						)
					)
				)
				(pin passive line
					(at 5.08 0 180)
					(length 2.032)
					(name "~"
						(effects
							(font
								(size 1.27 1.27)
							)
						)
					)
					(number "2"
						(effects
							(font
								(size 1.27 1.27)
							)
						)
					)
				)
			)
		)
)
